FILE_TYPE = MACRO_DRAWING;
SET COLOR_WIRE YELLOW;
SET COLOR_PROP MONO;
SET COLOR_DOT WHITE;
SET COLOR_ARC YELLOW;
SET COLOR_BODY GREEN;
SET COLOR_NOTE MONO;
SET PROP_DISPLAY VALUE;
SET PAGE_NUMBER P78;
FORCEADD GND..1
(-2675 625);
FORCEPROP 3 LASTPIN (-2675 675) SIG_NAME GND\g
J 0
(-2665 685);
DISPLAY 0.659574 (-2665 685);
PAINT MONO (-2665 685);
DISPLAY INVISIBLE (-2665 685);
FORCEPROP 1 LAST VOLTAGE 0.0V
J 0
(-2720 582);
DISPLAY 0.340426 (-2720 582);
PAINT SKYBLUE (-2720 582);
DISPLAY INVISIBLE (-2720 582);
FORCEPROP 1 LAST SIZE 1B
J 0
(-2600 575);
DISPLAY 1.787234 (-2600 575);
PAINT GREEN (-2600 575);
DISPLAY INVISIBLE (-2600 575);
FORCEPROP 2 LAST CDS_LIB mstr_symbols
J 0
(-2675 625);
PAINT ORANGE (-2675 625);
DISPLAY INVISIBLE (-2675 625);
FORCEPROP 2 LAST BOM_COST MEM
J 0
(-2675 630);
PAINT ORANGE (-2675 630);
DISPLAY INVISIBLE (-2675 630);
FORCEPROP 1 LAST BODY_TYPE PLUMBING
J 0
(-2720 582);
DISPLAY 0.340426 (-2720 582);
PAINT GREEN (-2720 582);
DISPLAY INVISIBLE (-2720 582);
FORCEPROP 1 LAST PATH I1
J 0
(-2600 625);
DISPLAY 0.872340 (-2600 625);
PAINT AQUA (-2600 625);
DISPLAY INVISIBLE (-2600 625);
FORCEPROP 2 LAST ROOM DDR4_GH_G
J 0
(-2675 630);
PAINT ORANGE (-2675 630);
DISPLAY INVISIBLE (-2675 630);
FORCEPROP 1 LAST HDL_POWER GND
J 0
(-2675 775);
DISPLAY 1.404255 (-2675 775);
PAINT GREEN (-2675 775);
DISPLAY INVISIBLE (-2675 775);
FORCEADD OFFPAGE..6
(-2025 1225);
FORCEPROP 2 LASTPIN (-1975 1225) SIG_NAME SMB_DDR_GHJ_VPP_SDA
J 0
(-1935 1235);
DISPLAY 0.617021 (-1935 1235);
PAINT ORANGE (-1935 1235);
FORCEPROP 2 LAST $XR5 99 
J 0
(-2724 1225);
DISPLAY 0.638298 (-2724 1225);
PAINT MONO (-2724 1225);
FORCEPROP 2 LAST $XR4 82 
J 0
(-2634 1225);
DISPLAY 0.638298 (-2634 1225);
PAINT MONO (-2634 1225);
FORCEPROP 2 LAST $XR3 81 
J 0
(-2544 1225);
DISPLAY 0.638298 (-2544 1225);
PAINT MONO (-2544 1225);
FORCEPROP 2 LAST $XR2 80 
J 0
(-2454 1225);
DISPLAY 0.638298 (-2454 1225);
PAINT MONO (-2454 1225);
FORCEPROP 2 LAST $XR1 79 
J 0
(-2364 1225);
DISPLAY 0.638298 (-2364 1225);
PAINT MONO (-2364 1225);
FORCEPROP 2 LAST $XR0 77 
J 0
(-2274 1225);
DISPLAY 0.638298 (-2274 1225);
PAINT MONO (-2274 1225);
FORCEPROP 2 LAST CDS_LIB mstr_standard
J 0
(-2025 1225);
DISPLAY 0.787234 (-2025 1225);
PAINT MONO (-2025 1225);
DISPLAY INVISIBLE (-2025 1225);
FORCEPROP 1 LAST OFFPAGE TRUE
J 0
(-1700 1100);
DISPLAY 0.936170 (-1700 1100);
PAINT GREEN (-1700 1100);
DISPLAY INVISIBLE (-1700 1100);
FORCEPROP 1 LAST COMMENT_BODY TRUE
J 0
(-1925 1150);
DISPLAY 0.936170 (-1925 1150);
PAINT GREEN (-1925 1150);
DISPLAY INVISIBLE (-1925 1150);
FORCEPROP 2 LAST PATH I10
J 0
(-2250 1275);
DISPLAY 1.021277 (-2250 1275);
PAINT ORANGE (-2250 1275);
DISPLAY INVISIBLE (-2250 1275);
FORCEADD TAP..6
R 2
(125 2925);
FORCEPROP 3 LASTPIN (75 2925) SIG_NAME M_G_DQ<37>
J 0
(85 2935);
DISPLAY 0.659574 (85 2935);
PAINT MONO (85 2935);
DISPLAY INVISIBLE (85 2935);
FORCEPROP 1 LASTPIN (75 2925) BN 37
J 2
(125 2935);
DISPLAY 0.617021 (125 2935);
PAINT PINK (125 2935);
FORCEPROP 2 LAST CDS_LIB mstr_standard
J 2
(125 2925);
DISPLAY 0.787234 (125 2925);
PAINT MONO (125 2925);
DISPLAY INVISIBLE (125 2925);
FORCEPROP 1 LAST BODY_TYPE PLUMBING
J 2
(125 2875);
DISPLAY 1.234043 (125 2875);
PAINT GREEN (125 2875);
DISPLAY INVISIBLE (125 2875);
FORCEPROP 1 LAST HDL_TAP TRUE
J 2
(-200 2800);
DISPLAY 1.234043 (-200 2800);
PAINT GREEN (-200 2800);
DISPLAY INVISIBLE (-200 2800);
FORCEPROP 1 LAST PATH I100
J 2
(127 2925);
DISPLAY 0.872340 (127 2925);
PAINT GREEN (127 2925);
DISPLAY INVISIBLE (127 2925);
FORCEADD TAP..6
R 2
(125 3125);
FORCEPROP 3 LASTPIN (75 3125) SIG_NAME M_G_DQ<41>
J 0
(85 3135);
DISPLAY 0.659574 (85 3135);
PAINT MONO (85 3135);
DISPLAY INVISIBLE (85 3135);
FORCEPROP 1 LASTPIN (75 3125) BN 41
J 2
(125 3135);
DISPLAY 0.617021 (125 3135);
PAINT PINK (125 3135);
FORCEPROP 2 LAST CDS_LIB mstr_standard
J 2
(125 3125);
DISPLAY 0.787234 (125 3125);
PAINT MONO (125 3125);
DISPLAY INVISIBLE (125 3125);
FORCEPROP 1 LAST BODY_TYPE PLUMBING
J 2
(125 3075);
DISPLAY 1.234043 (125 3075);
PAINT GREEN (125 3075);
DISPLAY INVISIBLE (125 3075);
FORCEPROP 1 LAST HDL_TAP TRUE
J 2
(-200 3000);
DISPLAY 1.234043 (-200 3000);
PAINT GREEN (-200 3000);
DISPLAY INVISIBLE (-200 3000);
FORCEPROP 1 LAST PATH I101
J 2
(127 3125);
DISPLAY 0.872340 (127 3125);
PAINT GREEN (127 3125);
DISPLAY INVISIBLE (127 3125);
FORCEADD TAP..6
R 2
(125 3025);
FORCEPROP 3 LASTPIN (75 3025) SIG_NAME M_G_DQ<39>
J 0
(85 3035);
DISPLAY 0.659574 (85 3035);
PAINT MONO (85 3035);
DISPLAY INVISIBLE (85 3035);
FORCEPROP 1 LASTPIN (75 3025) BN 39
J 2
(125 3035);
DISPLAY 0.617021 (125 3035);
PAINT PINK (125 3035);
FORCEPROP 2 LAST CDS_LIB mstr_standard
J 2
(125 3025);
DISPLAY 0.787234 (125 3025);
PAINT MONO (125 3025);
DISPLAY INVISIBLE (125 3025);
FORCEPROP 1 LAST BODY_TYPE PLUMBING
J 2
(125 2975);
DISPLAY 1.234043 (125 2975);
PAINT GREEN (125 2975);
DISPLAY INVISIBLE (125 2975);
FORCEPROP 1 LAST HDL_TAP TRUE
J 2
(-200 2900);
DISPLAY 1.234043 (-200 2900);
PAINT GREEN (-200 2900);
DISPLAY INVISIBLE (-200 2900);
FORCEPROP 1 LAST PATH I102
J 2
(127 3025);
DISPLAY 0.872340 (127 3025);
PAINT GREEN (127 3025);
DISPLAY INVISIBLE (127 3025);
FORCEADD TAP..6
R 2
(125 3075);
FORCEPROP 3 LASTPIN (75 3075) SIG_NAME M_G_DQ<40>
J 0
(85 3085);
DISPLAY 0.659574 (85 3085);
PAINT MONO (85 3085);
DISPLAY INVISIBLE (85 3085);
FORCEPROP 1 LASTPIN (75 3075) BN 40
J 2
(125 3085);
DISPLAY 0.617021 (125 3085);
PAINT PINK (125 3085);
FORCEPROP 2 LAST CDS_LIB mstr_standard
J 2
(125 3075);
DISPLAY 0.787234 (125 3075);
PAINT MONO (125 3075);
DISPLAY INVISIBLE (125 3075);
FORCEPROP 1 LAST BODY_TYPE PLUMBING
J 2
(125 3025);
DISPLAY 1.234043 (125 3025);
PAINT GREEN (125 3025);
DISPLAY INVISIBLE (125 3025);
FORCEPROP 1 LAST HDL_TAP TRUE
J 2
(-200 2950);
DISPLAY 1.234043 (-200 2950);
PAINT GREEN (-200 2950);
DISPLAY INVISIBLE (-200 2950);
FORCEPROP 1 LAST PATH I103
J 2
(127 3075);
DISPLAY 0.872340 (127 3075);
PAINT GREEN (127 3075);
DISPLAY INVISIBLE (127 3075);
FORCEADD TAP..6
R 2
(125 3175);
FORCEPROP 3 LASTPIN (75 3175) SIG_NAME M_G_DQ<42>
J 0
(85 3185);
DISPLAY 0.659574 (85 3185);
PAINT MONO (85 3185);
DISPLAY INVISIBLE (85 3185);
FORCEPROP 1 LASTPIN (75 3175) BN 42
J 2
(125 3185);
DISPLAY 0.617021 (125 3185);
PAINT PINK (125 3185);
FORCEPROP 2 LAST CDS_LIB mstr_standard
J 2
(125 3175);
DISPLAY 0.787234 (125 3175);
PAINT MONO (125 3175);
DISPLAY INVISIBLE (125 3175);
FORCEPROP 1 LAST BODY_TYPE PLUMBING
J 2
(125 3125);
DISPLAY 1.234043 (125 3125);
PAINT GREEN (125 3125);
DISPLAY INVISIBLE (125 3125);
FORCEPROP 1 LAST HDL_TAP TRUE
J 2
(-200 3050);
DISPLAY 1.234043 (-200 3050);
PAINT GREEN (-200 3050);
DISPLAY INVISIBLE (-200 3050);
FORCEPROP 1 LAST PATH I104
J 2
(127 3175);
DISPLAY 0.872340 (127 3175);
PAINT GREEN (127 3175);
DISPLAY INVISIBLE (127 3175);
FORCEADD TAP..6
R 2
(125 3225);
FORCEPROP 3 LASTPIN (75 3225) SIG_NAME M_G_DQ<43>
J 0
(85 3235);
DISPLAY 0.659574 (85 3235);
PAINT MONO (85 3235);
DISPLAY INVISIBLE (85 3235);
FORCEPROP 1 LASTPIN (75 3225) BN 43
J 2
(125 3235);
DISPLAY 0.617021 (125 3235);
PAINT PINK (125 3235);
FORCEPROP 2 LAST CDS_LIB mstr_standard
J 2
(125 3225);
DISPLAY 0.787234 (125 3225);
PAINT MONO (125 3225);
DISPLAY INVISIBLE (125 3225);
FORCEPROP 1 LAST BODY_TYPE PLUMBING
J 2
(125 3175);
DISPLAY 1.234043 (125 3175);
PAINT GREEN (125 3175);
DISPLAY INVISIBLE (125 3175);
FORCEPROP 1 LAST HDL_TAP TRUE
J 2
(-200 3100);
DISPLAY 1.234043 (-200 3100);
PAINT GREEN (-200 3100);
DISPLAY INVISIBLE (-200 3100);
FORCEPROP 1 LAST PATH I105
J 2
(127 3225);
DISPLAY 0.872340 (127 3225);
PAINT GREEN (127 3225);
DISPLAY INVISIBLE (127 3225);
FORCEADD TAP..6
R 2
(125 3275);
FORCEPROP 3 LASTPIN (75 3275) SIG_NAME M_G_DQ<44>
J 0
(85 3285);
DISPLAY 0.659574 (85 3285);
PAINT MONO (85 3285);
DISPLAY INVISIBLE (85 3285);
FORCEPROP 1 LASTPIN (75 3275) BN 44
J 2
(125 3285);
DISPLAY 0.617021 (125 3285);
PAINT PINK (125 3285);
FORCEPROP 2 LAST CDS_LIB mstr_standard
J 2
(125 3275);
DISPLAY 0.787234 (125 3275);
PAINT MONO (125 3275);
DISPLAY INVISIBLE (125 3275);
FORCEPROP 1 LAST BODY_TYPE PLUMBING
J 2
(125 3225);
DISPLAY 1.234043 (125 3225);
PAINT GREEN (125 3225);
DISPLAY INVISIBLE (125 3225);
FORCEPROP 1 LAST HDL_TAP TRUE
J 2
(-200 3150);
DISPLAY 1.234043 (-200 3150);
PAINT GREEN (-200 3150);
DISPLAY INVISIBLE (-200 3150);
FORCEPROP 1 LAST PATH I106
J 2
(127 3275);
DISPLAY 0.872340 (127 3275);
PAINT GREEN (127 3275);
DISPLAY INVISIBLE (127 3275);
FORCEADD TAP..6
R 2
(125 3325);
FORCEPROP 3 LASTPIN (75 3325) SIG_NAME M_G_DQ<45>
J 0
(85 3335);
DISPLAY 0.659574 (85 3335);
PAINT MONO (85 3335);
DISPLAY INVISIBLE (85 3335);
FORCEPROP 1 LASTPIN (75 3325) BN 45
J 2
(125 3335);
DISPLAY 0.617021 (125 3335);
PAINT PINK (125 3335);
FORCEPROP 2 LAST CDS_LIB mstr_standard
J 2
(125 3325);
DISPLAY 0.787234 (125 3325);
PAINT MONO (125 3325);
DISPLAY INVISIBLE (125 3325);
FORCEPROP 1 LAST BODY_TYPE PLUMBING
J 2
(125 3275);
DISPLAY 1.234043 (125 3275);
PAINT GREEN (125 3275);
DISPLAY INVISIBLE (125 3275);
FORCEPROP 1 LAST HDL_TAP TRUE
J 2
(-200 3200);
DISPLAY 1.234043 (-200 3200);
PAINT GREEN (-200 3200);
DISPLAY INVISIBLE (-200 3200);
FORCEPROP 1 LAST PATH I107
J 2
(127 3325);
DISPLAY 0.872340 (127 3325);
PAINT GREEN (127 3325);
DISPLAY INVISIBLE (127 3325);
FORCEADD TAP..6
R 2
(125 3375);
FORCEPROP 3 LASTPIN (75 3375) SIG_NAME M_G_DQ<46>
J 0
(85 3385);
DISPLAY 0.659574 (85 3385);
PAINT MONO (85 3385);
DISPLAY INVISIBLE (85 3385);
FORCEPROP 1 LASTPIN (75 3375) BN 46
J 2
(125 3385);
DISPLAY 0.617021 (125 3385);
PAINT PINK (125 3385);
FORCEPROP 2 LAST CDS_LIB mstr_standard
J 2
(125 3375);
DISPLAY 0.787234 (125 3375);
PAINT MONO (125 3375);
DISPLAY INVISIBLE (125 3375);
FORCEPROP 1 LAST BODY_TYPE PLUMBING
J 2
(125 3325);
DISPLAY 1.234043 (125 3325);
PAINT GREEN (125 3325);
DISPLAY INVISIBLE (125 3325);
FORCEPROP 1 LAST HDL_TAP TRUE
J 2
(-200 3250);
DISPLAY 1.234043 (-200 3250);
PAINT GREEN (-200 3250);
DISPLAY INVISIBLE (-200 3250);
FORCEPROP 1 LAST PATH I108
J 2
(127 3375);
DISPLAY 0.872340 (127 3375);
PAINT GREEN (127 3375);
DISPLAY INVISIBLE (127 3375);
FORCEADD TAP..6
R 2
(125 3475);
FORCEPROP 3 LASTPIN (75 3475) SIG_NAME M_G_DQ<48>
J 0
(85 3485);
DISPLAY 0.659574 (85 3485);
PAINT MONO (85 3485);
DISPLAY INVISIBLE (85 3485);
FORCEPROP 1 LASTPIN (75 3475) BN 48
J 2
(125 3485);
DISPLAY 0.617021 (125 3485);
PAINT PINK (125 3485);
FORCEPROP 2 LAST CDS_LIB mstr_standard
J 2
(125 3475);
DISPLAY 0.787234 (125 3475);
PAINT MONO (125 3475);
DISPLAY INVISIBLE (125 3475);
FORCEPROP 1 LAST BODY_TYPE PLUMBING
J 2
(125 3425);
DISPLAY 1.234043 (125 3425);
PAINT GREEN (125 3425);
DISPLAY INVISIBLE (125 3425);
FORCEPROP 1 LAST HDL_TAP TRUE
J 2
(-200 3350);
DISPLAY 1.234043 (-200 3350);
PAINT GREEN (-200 3350);
DISPLAY INVISIBLE (-200 3350);
FORCEPROP 1 LAST PATH I109
J 2
(127 3475);
DISPLAY 0.872340 (127 3475);
PAINT GREEN (127 3475);
DISPLAY INVISIBLE (127 3475);
FORCEADD OFFPAGE..1
(-2175 1525);
FORCEPROP 2 LAST $XR1 77 
J 0
(-2516 1525);
DISPLAY 0.638298 (-2516 1525);
PAINT MONO (-2516 1525);
FORCEPROP 2 LAST $XR0 57 
J 0
(-2426 1525);
DISPLAY 0.638298 (-2426 1525);
PAINT MONO (-2426 1525);
FORCEPROP 2 LAST CDS_LIB mstr_standard
J 0
(-2175 1525);
DISPLAY 0.787234 (-2175 1525);
PAINT MONO (-2175 1525);
DISPLAY INVISIBLE (-2175 1525);
FORCEPROP 1 LAST OFFPAGE TRUE
J 0
(-1850 1400);
DISPLAY 0.936170 (-1850 1400);
PAINT GREEN (-1850 1400);
DISPLAY INVISIBLE (-1850 1400);
FORCEPROP 1 LAST COMMENT_BODY TRUE
J 0
(-2050 1425);
DISPLAY 0.936170 (-2050 1425);
PAINT GREEN (-2050 1425);
DISPLAY INVISIBLE (-2050 1425);
FORCEPROP 2 LAST PATH I11
J 0
(-2425 1575);
DISPLAY 1.021277 (-2425 1575);
PAINT ORANGE (-2425 1575);
DISPLAY INVISIBLE (-2425 1575);
FORCEADD TAP..6
R 2
(125 3425);
FORCEPROP 3 LASTPIN (75 3425) SIG_NAME M_G_DQ<47>
J 0
(85 3435);
DISPLAY 0.659574 (85 3435);
PAINT MONO (85 3435);
DISPLAY INVISIBLE (85 3435);
FORCEPROP 1 LASTPIN (75 3425) BN 47
J 2
(125 3435);
DISPLAY 0.617021 (125 3435);
PAINT PINK (125 3435);
FORCEPROP 2 LAST CDS_LIB mstr_standard
J 2
(125 3425);
DISPLAY 0.787234 (125 3425);
PAINT MONO (125 3425);
DISPLAY INVISIBLE (125 3425);
FORCEPROP 1 LAST BODY_TYPE PLUMBING
J 2
(125 3375);
DISPLAY 1.234043 (125 3375);
PAINT GREEN (125 3375);
DISPLAY INVISIBLE (125 3375);
FORCEPROP 1 LAST HDL_TAP TRUE
J 2
(-200 3300);
DISPLAY 1.234043 (-200 3300);
PAINT GREEN (-200 3300);
DISPLAY INVISIBLE (-200 3300);
FORCEPROP 1 LAST PATH I110
J 2
(127 3425);
DISPLAY 0.872340 (127 3425);
PAINT GREEN (127 3425);
DISPLAY INVISIBLE (127 3425);
FORCEADD TAP..6
R 2
(125 3525);
FORCEPROP 3 LASTPIN (75 3525) SIG_NAME M_G_DQ<49>
J 0
(85 3535);
DISPLAY 0.659574 (85 3535);
PAINT MONO (85 3535);
DISPLAY INVISIBLE (85 3535);
FORCEPROP 1 LASTPIN (75 3525) BN 49
J 2
(125 3535);
DISPLAY 0.617021 (125 3535);
PAINT PINK (125 3535);
FORCEPROP 2 LAST CDS_LIB mstr_standard
J 2
(125 3525);
DISPLAY 0.787234 (125 3525);
PAINT MONO (125 3525);
DISPLAY INVISIBLE (125 3525);
FORCEPROP 1 LAST BODY_TYPE PLUMBING
J 2
(125 3475);
DISPLAY 1.234043 (125 3475);
PAINT GREEN (125 3475);
DISPLAY INVISIBLE (125 3475);
FORCEPROP 1 LAST HDL_TAP TRUE
J 2
(-200 3400);
DISPLAY 1.234043 (-200 3400);
PAINT GREEN (-200 3400);
DISPLAY INVISIBLE (-200 3400);
FORCEPROP 1 LAST PATH I111
J 2
(127 3525);
DISPLAY 0.872340 (127 3525);
PAINT GREEN (127 3525);
DISPLAY INVISIBLE (127 3525);
FORCEADD TAP..6
R 2
(125 3575);
FORCEPROP 3 LASTPIN (75 3575) SIG_NAME M_G_DQ<50>
J 0
(85 3585);
DISPLAY 0.659574 (85 3585);
PAINT MONO (85 3585);
DISPLAY INVISIBLE (85 3585);
FORCEPROP 1 LASTPIN (75 3575) BN 50
J 2
(125 3585);
DISPLAY 0.617021 (125 3585);
PAINT PINK (125 3585);
FORCEPROP 2 LAST CDS_LIB mstr_standard
J 2
(125 3575);
DISPLAY 0.787234 (125 3575);
PAINT MONO (125 3575);
DISPLAY INVISIBLE (125 3575);
FORCEPROP 1 LAST BODY_TYPE PLUMBING
J 2
(125 3525);
DISPLAY 1.234043 (125 3525);
PAINT GREEN (125 3525);
DISPLAY INVISIBLE (125 3525);
FORCEPROP 1 LAST HDL_TAP TRUE
J 2
(-200 3450);
DISPLAY 1.234043 (-200 3450);
PAINT GREEN (-200 3450);
DISPLAY INVISIBLE (-200 3450);
FORCEPROP 1 LAST PATH I112
J 2
(127 3575);
DISPLAY 0.872340 (127 3575);
PAINT GREEN (127 3575);
DISPLAY INVISIBLE (127 3575);
FORCEADD TAP..6
R 2
(125 3625);
FORCEPROP 3 LASTPIN (75 3625) SIG_NAME M_G_DQ<51>
J 0
(85 3635);
DISPLAY 0.659574 (85 3635);
PAINT MONO (85 3635);
DISPLAY INVISIBLE (85 3635);
FORCEPROP 1 LASTPIN (75 3625) BN 51
J 2
(125 3635);
DISPLAY 0.617021 (125 3635);
PAINT PINK (125 3635);
FORCEPROP 2 LAST CDS_LIB mstr_standard
J 2
(125 3625);
DISPLAY 0.787234 (125 3625);
PAINT MONO (125 3625);
DISPLAY INVISIBLE (125 3625);
FORCEPROP 1 LAST BODY_TYPE PLUMBING
J 2
(125 3575);
DISPLAY 1.234043 (125 3575);
PAINT GREEN (125 3575);
DISPLAY INVISIBLE (125 3575);
FORCEPROP 1 LAST HDL_TAP TRUE
J 2
(-200 3500);
DISPLAY 1.234043 (-200 3500);
PAINT GREEN (-200 3500);
DISPLAY INVISIBLE (-200 3500);
FORCEPROP 1 LAST PATH I113
J 2
(127 3625);
DISPLAY 0.872340 (127 3625);
PAINT GREEN (127 3625);
DISPLAY INVISIBLE (127 3625);
FORCEADD TAP..6
R 2
(125 3775);
FORCEPROP 3 LASTPIN (75 3775) SIG_NAME M_G_DQ<54>
J 0
(85 3785);
DISPLAY 0.659574 (85 3785);
PAINT MONO (85 3785);
DISPLAY INVISIBLE (85 3785);
FORCEPROP 1 LASTPIN (75 3775) BN 54
J 2
(125 3785);
DISPLAY 0.617021 (125 3785);
PAINT PINK (125 3785);
FORCEPROP 2 LAST CDS_LIB mstr_standard
J 2
(125 3775);
DISPLAY 0.787234 (125 3775);
PAINT MONO (125 3775);
DISPLAY INVISIBLE (125 3775);
FORCEPROP 1 LAST BODY_TYPE PLUMBING
J 2
(125 3725);
DISPLAY 1.234043 (125 3725);
PAINT GREEN (125 3725);
DISPLAY INVISIBLE (125 3725);
FORCEPROP 1 LAST HDL_TAP TRUE
J 2
(-200 3650);
DISPLAY 1.234043 (-200 3650);
PAINT GREEN (-200 3650);
DISPLAY INVISIBLE (-200 3650);
FORCEPROP 1 LAST PATH I114
J 2
(127 3775);
DISPLAY 0.872340 (127 3775);
PAINT GREEN (127 3775);
DISPLAY INVISIBLE (127 3775);
FORCEADD TAP..6
R 2
(125 3725);
FORCEPROP 3 LASTPIN (75 3725) SIG_NAME M_G_DQ<53>
J 0
(85 3735);
DISPLAY 0.659574 (85 3735);
PAINT MONO (85 3735);
DISPLAY INVISIBLE (85 3735);
FORCEPROP 1 LASTPIN (75 3725) BN 53
J 2
(125 3735);
DISPLAY 0.617021 (125 3735);
PAINT PINK (125 3735);
FORCEPROP 2 LAST CDS_LIB mstr_standard
J 2
(125 3725);
DISPLAY 0.787234 (125 3725);
PAINT MONO (125 3725);
DISPLAY INVISIBLE (125 3725);
FORCEPROP 1 LAST BODY_TYPE PLUMBING
J 2
(125 3675);
DISPLAY 1.234043 (125 3675);
PAINT GREEN (125 3675);
DISPLAY INVISIBLE (125 3675);
FORCEPROP 1 LAST HDL_TAP TRUE
J 2
(-200 3600);
DISPLAY 1.234043 (-200 3600);
PAINT GREEN (-200 3600);
DISPLAY INVISIBLE (-200 3600);
FORCEPROP 1 LAST PATH I115
J 2
(127 3725);
DISPLAY 0.872340 (127 3725);
PAINT GREEN (127 3725);
DISPLAY INVISIBLE (127 3725);
FORCEADD TAP..6
R 2
(125 3675);
FORCEPROP 3 LASTPIN (75 3675) SIG_NAME M_G_DQ<52>
J 0
(85 3685);
DISPLAY 0.659574 (85 3685);
PAINT MONO (85 3685);
DISPLAY INVISIBLE (85 3685);
FORCEPROP 1 LASTPIN (75 3675) BN 52
J 2
(125 3685);
DISPLAY 0.617021 (125 3685);
PAINT PINK (125 3685);
FORCEPROP 2 LAST CDS_LIB mstr_standard
J 2
(125 3675);
DISPLAY 0.787234 (125 3675);
PAINT MONO (125 3675);
DISPLAY INVISIBLE (125 3675);
FORCEPROP 1 LAST BODY_TYPE PLUMBING
J 2
(125 3625);
DISPLAY 1.234043 (125 3625);
PAINT GREEN (125 3625);
DISPLAY INVISIBLE (125 3625);
FORCEPROP 1 LAST HDL_TAP TRUE
J 2
(-200 3550);
DISPLAY 1.234043 (-200 3550);
PAINT GREEN (-200 3550);
DISPLAY INVISIBLE (-200 3550);
FORCEPROP 1 LAST PATH I116
J 2
(127 3675);
DISPLAY 0.872340 (127 3675);
PAINT GREEN (127 3675);
DISPLAY INVISIBLE (127 3675);
FORCEADD TAP..6
R 2
(125 3825);
FORCEPROP 3 LASTPIN (75 3825) SIG_NAME M_G_DQ<55>
J 0
(85 3835);
DISPLAY 0.659574 (85 3835);
PAINT MONO (85 3835);
DISPLAY INVISIBLE (85 3835);
FORCEPROP 1 LASTPIN (75 3825) BN 55
J 2
(125 3835);
DISPLAY 0.617021 (125 3835);
PAINT PINK (125 3835);
FORCEPROP 2 LAST CDS_LIB mstr_standard
J 2
(125 3825);
DISPLAY 0.787234 (125 3825);
PAINT MONO (125 3825);
DISPLAY INVISIBLE (125 3825);
FORCEPROP 1 LAST BODY_TYPE PLUMBING
J 2
(125 3775);
DISPLAY 1.234043 (125 3775);
PAINT GREEN (125 3775);
DISPLAY INVISIBLE (125 3775);
FORCEPROP 1 LAST HDL_TAP TRUE
J 2
(-200 3700);
DISPLAY 1.234043 (-200 3700);
PAINT GREEN (-200 3700);
DISPLAY INVISIBLE (-200 3700);
FORCEPROP 1 LAST PATH I117
J 2
(127 3825);
DISPLAY 0.872340 (127 3825);
PAINT GREEN (127 3825);
DISPLAY INVISIBLE (127 3825);
FORCEADD TAP..6
R 2
(125 3875);
FORCEPROP 3 LASTPIN (75 3875) SIG_NAME M_G_DQ<56>
J 0
(85 3885);
DISPLAY 0.659574 (85 3885);
PAINT MONO (85 3885);
DISPLAY INVISIBLE (85 3885);
FORCEPROP 1 LASTPIN (75 3875) BN 56
J 2
(125 3885);
DISPLAY 0.617021 (125 3885);
PAINT PINK (125 3885);
FORCEPROP 2 LAST CDS_LIB mstr_standard
J 2
(125 3875);
DISPLAY 0.787234 (125 3875);
PAINT MONO (125 3875);
DISPLAY INVISIBLE (125 3875);
FORCEPROP 1 LAST BODY_TYPE PLUMBING
J 2
(125 3825);
DISPLAY 1.234043 (125 3825);
PAINT GREEN (125 3825);
DISPLAY INVISIBLE (125 3825);
FORCEPROP 1 LAST HDL_TAP TRUE
J 2
(-200 3750);
DISPLAY 1.234043 (-200 3750);
PAINT GREEN (-200 3750);
DISPLAY INVISIBLE (-200 3750);
FORCEPROP 1 LAST PATH I118
J 2
(127 3875);
DISPLAY 0.872340 (127 3875);
PAINT GREEN (127 3875);
DISPLAY INVISIBLE (127 3875);
FORCEADD PVPP_GHJ..1
(750 2750);
FORCEPROP 3 LASTPIN (750 2700) SIG_NAME PVPP_GHJ\g
J 0
(760 2710);
DISPLAY 0.659574 (760 2710);
PAINT MONO (760 2710);
DISPLAY INVISIBLE (760 2710);
FORCEPROP 1 LAST VOLTAGE 2.5V
J 0
(705 2707);
DISPLAY 0.340426 (705 2707);
PAINT SKYBLUE (705 2707);
DISPLAY INVISIBLE (705 2707);
FORCEPROP 0 LAST BOM_COST MEM
J 0
(750 2850);
PAINT ORANGE (750 2850);
DISPLAY INVISIBLE (750 2850);
FORCEPROP 2 LAST CDS_LIB mstr_symbols
J 0
(750 2750);
PAINT ORANGE (750 2750);
DISPLAY INVISIBLE (750 2750);
FORCEPROP 1 LAST BODY_TYPE PLUMBING
J 0
(705 2707);
DISPLAY 0.340426 (705 2707);
PAINT GREEN (705 2707);
DISPLAY INVISIBLE (705 2707);
FORCEPROP 1 LAST PATH I119
J 0
(800 2775);
DISPLAY 0.872340 (800 2775);
PAINT AQUA (800 2775);
DISPLAY INVISIBLE (800 2775);
FORCEPROP 2 LAST ROOM DDR4_GH_G
J 0
(750 2850);
PAINT ORANGE (750 2850);
DISPLAY INVISIBLE (750 2850);
FORCEPROP 1 LAST HDL_POWER PVPP_GHJ
J 1
(750 2800);
DISPLAY 0.872340 (750 2800);
PAINT GREEN (750 2800);
DISPLAY INVISIBLE (750 2800);
FORCEADD TAP..6
(-1375 1825);
FORCEPROP 3 LASTPIN (-1325 1825) SIG_NAME M_G_ECC<0>
J 0
(-1315 1835);
DISPLAY 0.659574 (-1315 1835);
PAINT MONO (-1315 1835);
DISPLAY INVISIBLE (-1315 1835);
FORCEPROP 1 LASTPIN (-1325 1825) BN 0
J 0
(-1375 1835);
DISPLAY 0.617021 (-1375 1835);
PAINT PINK (-1375 1835);
FORCEPROP 2 LAST CDS_LIB mstr_standard
J 0
(-1375 1825);
DISPLAY 0.787234 (-1375 1825);
PAINT MONO (-1375 1825);
DISPLAY INVISIBLE (-1375 1825);
FORCEPROP 1 LAST BODY_TYPE PLUMBING
J 0
(-1375 1775);
DISPLAY 1.234043 (-1375 1775);
PAINT GREEN (-1375 1775);
DISPLAY INVISIBLE (-1375 1775);
FORCEPROP 1 LAST HDL_TAP TRUE
J 0
(-1050 1700);
DISPLAY 1.234043 (-1050 1700);
PAINT GREEN (-1050 1700);
DISPLAY INVISIBLE (-1050 1700);
FORCEPROP 1 LAST PATH I12
J 0
(-1377 1825);
DISPLAY 0.872340 (-1377 1825);
PAINT GREEN (-1377 1825);
DISPLAY INVISIBLE (-1377 1825);
FORCEADD SCONN288_H44441003..2
(1750 4000);
FORCEPROP 1 LAST LOCATION J9T1
J 0
(1350 5100);
DISPLAY 0.617021 (1350 5100);
PAINT AQUA (1350 5100);
FORCEPROP 1 LAST PART_NUMBER H44441-003
J 0
(1350 2900);
DISPLAY 0.617021 (1350 2900);
PAINT BLUE (1350 2900);
FORCEPROP 1 LAST MATERIAL SCONN
J 0
(1350 5050);
DISPLAY 0.617021 (1350 5050);
PAINT SKYBLUE (1350 5050);
FORCEPROP 2 LASTPIN (2200 4850) $PN 51
J 0
(2210 4860);
DISPLAY 0.617021 (2210 4860);
PAINT ORANGE (2210 4860);
FORCEPROP 2 LASTPIN (2200 4800) $PN 52
J 0
(2210 4810);
DISPLAY 0.617021 (2210 4810);
PAINT ORANGE (2210 4810);
FORCEPROP 2 LASTPIN (2200 4750) $PN 132
J 0
(2210 4760);
DISPLAY 0.617021 (2210 4760);
PAINT ORANGE (2210 4760);
FORCEPROP 2 LASTPIN (2200 4700) $PN 133
J 0
(2210 4710);
DISPLAY 0.617021 (2210 4710);
PAINT ORANGE (2210 4710);
FORCEPROP 2 LASTPIN (2200 4650) $PN 121
J 0
(2210 4660);
DISPLAY 0.617021 (2210 4660);
PAINT ORANGE (2210 4660);
FORCEPROP 2 LASTPIN (2200 4600) $PN 122
J 0
(2210 4610);
DISPLAY 0.617021 (2210 4610);
PAINT ORANGE (2210 4610);
FORCEPROP 2 LASTPIN (2200 4550) $PN 110
J 0
(2210 4560);
DISPLAY 0.617021 (2210 4560);
PAINT ORANGE (2210 4560);
FORCEPROP 2 LASTPIN (2200 4500) $PN 111
J 0
(2210 4510);
DISPLAY 0.617021 (2210 4510);
PAINT ORANGE (2210 4510);
FORCEPROP 2 LASTPIN (2200 4450) $PN 99
J 0
(2210 4460);
DISPLAY 0.617021 (2210 4460);
PAINT ORANGE (2210 4460);
FORCEPROP 2 LASTPIN (2200 4400) $PN 100
J 0
(2210 4410);
DISPLAY 0.617021 (2210 4410);
PAINT ORANGE (2210 4410);
FORCEPROP 2 LASTPIN (2200 4350) $PN 40
J 0
(2210 4360);
DISPLAY 0.617021 (2210 4360);
PAINT ORANGE (2210 4360);
FORCEPROP 2 LASTPIN (2200 4300) $PN 41
J 0
(2210 4310);
DISPLAY 0.617021 (2210 4310);
PAINT ORANGE (2210 4310);
FORCEPROP 2 LASTPIN (2200 4250) $PN 29
J 0
(2210 4260);
DISPLAY 0.617021 (2210 4260);
PAINT ORANGE (2210 4260);
FORCEPROP 2 LASTPIN (2200 4200) $PN 30
J 0
(2210 4210);
DISPLAY 0.617021 (2210 4210);
PAINT ORANGE (2210 4210);
FORCEPROP 2 LASTPIN (2200 4150) $PN 18
J 0
(2210 4160);
DISPLAY 0.617021 (2210 4160);
PAINT ORANGE (2210 4160);
FORCEPROP 2 LASTPIN (2200 4100) $PN 19
J 0
(2210 4110);
DISPLAY 0.617021 (2210 4110);
PAINT ORANGE (2210 4110);
FORCEPROP 2 LASTPIN (2200 4050) $PN 7
J 0
(2210 4060);
DISPLAY 0.617021 (2210 4060);
PAINT ORANGE (2210 4060);
FORCEPROP 2 LASTPIN (2200 4000) $PN 8
J 0
(2210 4010);
DISPLAY 0.617021 (2210 4010);
PAINT ORANGE (2210 4010);
FORCEPROP 2 LASTPIN (2200 3950) $PN 197
J 0
(2210 3960);
DISPLAY 0.617021 (2210 3960);
PAINT ORANGE (2210 3960);
FORCEPROP 2 LASTPIN (2200 3900) $PN 196
J 0
(2210 3910);
DISPLAY 0.617021 (2210 3910);
PAINT ORANGE (2210 3910);
FORCEPROP 2 LASTPIN (2200 3850) $PN 278
J 0
(2210 3860);
DISPLAY 0.617021 (2210 3860);
PAINT ORANGE (2210 3860);
FORCEPROP 2 LASTPIN (2200 3800) $PN 277
J 0
(2210 3810);
DISPLAY 0.617021 (2210 3810);
PAINT ORANGE (2210 3810);
FORCEPROP 2 LASTPIN (2200 3750) $PN 267
J 0
(2210 3760);
DISPLAY 0.617021 (2210 3760);
PAINT ORANGE (2210 3760);
FORCEPROP 2 LASTPIN (2200 3700) $PN 266
J 0
(2210 3710);
DISPLAY 0.617021 (2210 3710);
PAINT ORANGE (2210 3710);
FORCEPROP 2 LASTPIN (2200 3650) $PN 256
J 0
(2210 3660);
DISPLAY 0.617021 (2210 3660);
PAINT ORANGE (2210 3660);
FORCEPROP 2 LASTPIN (2200 3600) $PN 255
J 0
(2210 3610);
DISPLAY 0.617021 (2210 3610);
PAINT ORANGE (2210 3610);
FORCEPROP 2 LASTPIN (2200 3550) $PN 245
J 0
(2210 3560);
DISPLAY 0.617021 (2210 3560);
PAINT ORANGE (2210 3560);
FORCEPROP 2 LASTPIN (2200 3500) $PN 244
J 0
(2210 3510);
DISPLAY 0.617021 (2210 3510);
PAINT ORANGE (2210 3510);
FORCEPROP 2 LASTPIN (2200 3450) $PN 186
J 0
(2210 3460);
DISPLAY 0.617021 (2210 3460);
PAINT ORANGE (2210 3460);
FORCEPROP 2 LASTPIN (2200 3400) $PN 185
J 0
(2210 3410);
DISPLAY 0.617021 (2210 3410);
PAINT ORANGE (2210 3410);
FORCEPROP 2 LASTPIN (2200 3350) $PN 175
J 0
(2210 3360);
DISPLAY 0.617021 (2210 3360);
PAINT ORANGE (2210 3360);
FORCEPROP 2 LASTPIN (2200 3300) $PN 174
J 0
(2210 3310);
DISPLAY 0.617021 (2210 3310);
PAINT ORANGE (2210 3310);
FORCEPROP 2 LASTPIN (2200 3250) $PN 164
J 0
(2210 3260);
DISPLAY 0.617021 (2210 3260);
PAINT ORANGE (2210 3260);
FORCEPROP 2 LASTPIN (2200 3200) $PN 163
J 0
(2210 3210);
DISPLAY 0.617021 (2210 3210);
PAINT ORANGE (2210 3210);
FORCEPROP 2 LASTPIN (2200 3150) $PN 153
J 0
(2210 3160);
DISPLAY 0.617021 (2210 3160);
PAINT ORANGE (2210 3160);
FORCEPROP 2 LASTPIN (2200 3100) $PN 152
J 0
(2210 3110);
DISPLAY 0.617021 (2210 3110);
PAINT ORANGE (2210 3110);
FORCEPROP 0 LAST BOM_SS NOPOP
J 0
(1602 5041);
DISPLAY 1.021277 (1602 5041);
PAINT BROWN (1602 5041);
DISPLAY BOTH (1602 5041);
FORCEPROP 1 LAST PACK_TYPE PIP
J 0
(1350 5150);
PAINT SKYBLUE (1350 5150);
DISPLAY INVISIBLE (1350 5150);
FORCEPROP 2 LAST BOM_COST MEM
J 0
(1750 4000);
PAINT ORANGE (1750 4000);
DISPLAY INVISIBLE (1750 4000);
FORCEPROP 2 LAST CDS_LIB mstr_sconn
J 0
(1750 4000);
PAINT ORANGE (1750 4000);
DISPLAY INVISIBLE (1750 4000);
FORCEPROP 2 LAST SEC_TYPE PIP
J 0
(1350 5150);
DISPLAY 1.021277 (1350 5150);
PAINT ORANGE (1350 5150);
DISPLAY INVISIBLE (1350 5150);
FORCEPROP 2 LAST SEC 2
J 0
(1350 5150);
DISPLAY 0.680851 (1350 5150);
PAINT MONO (1350 5150);
DISPLAY INVISIBLE (1350 5150);
FORCEPROP 2 LAST CDS_LOCATION J9T1
J 0
(1350 5100);
DISPLAY 0.617021 (1350 5100);
PAINT AQUA (1350 5100);
DISPLAY INVISIBLE (1350 5100);
FORCEPROP 1 LAST PATH I120
J 0
(1750 5050);
PAINT GREEN (1750 5050);
DISPLAY INVISIBLE (1750 5050);
FORCEPROP 2 LAST ROOM DDR4_GH_G
J 0
(1750 4000);
PAINT ORANGE (1750 4000);
DISPLAY INVISIBLE (1750 4000);
FORCEADD OFFPAGE..1
(-2025 4275);
FORCEPROP 2 LAST $XR1 77 
J 0
(-2336 4275);
DISPLAY 0.638298 (-2336 4275);
PAINT MONO (-2336 4275);
FORCEPROP 2 LAST $XR0 57 
J 0
(-2246 4275);
DISPLAY 0.638298 (-2246 4275);
PAINT MONO (-2246 4275);
FORCEPROP 2 LAST CDS_LIB mstr_standard
J 0
(-2025 4275);
DISPLAY 0.787234 (-2025 4275);
PAINT MONO (-2025 4275);
DISPLAY INVISIBLE (-2025 4275);
FORCEPROP 1 LAST OFFPAGE TRUE
J 0
(-1700 4150);
DISPLAY 0.936170 (-1700 4150);
PAINT GREEN (-1700 4150);
DISPLAY INVISIBLE (-1700 4150);
FORCEPROP 1 LAST COMMENT_BODY TRUE
J 0
(-1900 4175);
DISPLAY 0.936170 (-1900 4175);
PAINT GREEN (-1900 4175);
DISPLAY INVISIBLE (-1900 4175);
FORCEPROP 2 LAST PATH I121
J 0
(-2225 4325);
DISPLAY 1.021277 (-2225 4325);
PAINT ORANGE (-2225 4325);
DISPLAY INVISIBLE (-2225 4325);
FORCEADD TAP..6
(-1375 3925);
FORCEPROP 3 LASTPIN (-1325 3925) SIG_NAME M_G_MA<11>
J 0
(-1315 3935);
DISPLAY 0.659574 (-1315 3935);
PAINT MONO (-1315 3935);
DISPLAY INVISIBLE (-1315 3935);
FORCEPROP 1 LASTPIN (-1325 3925) BN 11
J 0
(-1375 3935);
DISPLAY 0.617021 (-1375 3935);
PAINT PINK (-1375 3935);
FORCEPROP 2 LAST CDS_LIB mstr_standard
J 2
(-1375 3925);
DISPLAY 0.787234 (-1375 3925);
PAINT MONO (-1375 3925);
DISPLAY INVISIBLE (-1375 3925);
FORCEPROP 1 LAST BODY_TYPE PLUMBING
J 0
(-1375 3875);
DISPLAY 1.234043 (-1375 3875);
PAINT GREEN (-1375 3875);
DISPLAY INVISIBLE (-1375 3875);
FORCEPROP 1 LAST HDL_TAP TRUE
J 0
(-1050 3800);
DISPLAY 1.234043 (-1050 3800);
PAINT GREEN (-1050 3800);
DISPLAY INVISIBLE (-1050 3800);
FORCEPROP 1 LAST PATH I122
J 0
(-1377 3925);
DISPLAY 0.872340 (-1377 3925);
PAINT GREEN (-1377 3925);
DISPLAY INVISIBLE (-1377 3925);
FORCEADD TAP..6
(-1375 3975);
FORCEPROP 3 LASTPIN (-1325 3975) SIG_NAME M_G_MA<12>
J 0
(-1315 3985);
DISPLAY 0.659574 (-1315 3985);
PAINT MONO (-1315 3985);
DISPLAY INVISIBLE (-1315 3985);
FORCEPROP 1 LASTPIN (-1325 3975) BN 12
J 0
(-1375 3985);
DISPLAY 0.617021 (-1375 3985);
PAINT PINK (-1375 3985);
FORCEPROP 2 LAST CDS_LIB mstr_standard
J 2
(-1375 3975);
DISPLAY 0.787234 (-1375 3975);
PAINT MONO (-1375 3975);
DISPLAY INVISIBLE (-1375 3975);
FORCEPROP 1 LAST BODY_TYPE PLUMBING
J 0
(-1375 3925);
DISPLAY 1.234043 (-1375 3925);
PAINT GREEN (-1375 3925);
DISPLAY INVISIBLE (-1375 3925);
FORCEPROP 1 LAST HDL_TAP TRUE
J 0
(-1050 3850);
DISPLAY 1.234043 (-1050 3850);
PAINT GREEN (-1050 3850);
DISPLAY INVISIBLE (-1050 3850);
FORCEPROP 1 LAST PATH I123
J 0
(-1377 3975);
DISPLAY 0.872340 (-1377 3975);
PAINT GREEN (-1377 3975);
DISPLAY INVISIBLE (-1377 3975);
FORCEADD TAP..6
(-1375 4125);
FORCEPROP 3 LASTPIN (-1325 4125) SIG_NAME M_G_MA<15>
J 0
(-1315 4135);
DISPLAY 0.659574 (-1315 4135);
PAINT MONO (-1315 4135);
DISPLAY INVISIBLE (-1315 4135);
FORCEPROP 1 LASTPIN (-1325 4125) BN 15
J 0
(-1375 4135);
DISPLAY 0.617021 (-1375 4135);
PAINT PINK (-1375 4135);
FORCEPROP 2 LAST CDS_LIB mstr_standard
J 2
(-1375 4125);
DISPLAY 0.787234 (-1375 4125);
PAINT MONO (-1375 4125);
DISPLAY INVISIBLE (-1375 4125);
FORCEPROP 1 LAST BODY_TYPE PLUMBING
J 0
(-1375 4075);
DISPLAY 1.234043 (-1375 4075);
PAINT GREEN (-1375 4075);
DISPLAY INVISIBLE (-1375 4075);
FORCEPROP 1 LAST HDL_TAP TRUE
J 0
(-1050 4000);
DISPLAY 1.234043 (-1050 4000);
PAINT GREEN (-1050 4000);
DISPLAY INVISIBLE (-1050 4000);
FORCEPROP 1 LAST PATH I124
J 0
(-1377 4125);
DISPLAY 0.872340 (-1377 4125);
PAINT GREEN (-1377 4125);
DISPLAY INVISIBLE (-1377 4125);
FORCEADD TAP..6
(-1375 4075);
FORCEPROP 3 LASTPIN (-1325 4075) SIG_NAME M_G_MA<14>
J 0
(-1315 4085);
DISPLAY 0.659574 (-1315 4085);
PAINT MONO (-1315 4085);
DISPLAY INVISIBLE (-1315 4085);
FORCEPROP 1 LASTPIN (-1325 4075) BN 14
J 0
(-1375 4085);
DISPLAY 0.617021 (-1375 4085);
PAINT PINK (-1375 4085);
FORCEPROP 2 LAST CDS_LIB mstr_standard
J 2
(-1375 4075);
DISPLAY 0.787234 (-1375 4075);
PAINT MONO (-1375 4075);
DISPLAY INVISIBLE (-1375 4075);
FORCEPROP 1 LAST BODY_TYPE PLUMBING
J 0
(-1375 4025);
DISPLAY 1.234043 (-1375 4025);
PAINT GREEN (-1375 4025);
DISPLAY INVISIBLE (-1375 4025);
FORCEPROP 1 LAST HDL_TAP TRUE
J 0
(-1050 3950);
DISPLAY 1.234043 (-1050 3950);
PAINT GREEN (-1050 3950);
DISPLAY INVISIBLE (-1050 3950);
FORCEPROP 1 LAST PATH I125
J 0
(-1377 4075);
DISPLAY 0.872340 (-1377 4075);
PAINT GREEN (-1377 4075);
DISPLAY INVISIBLE (-1377 4075);
FORCEADD TAP..6
(-1375 4025);
FORCEPROP 3 LASTPIN (-1325 4025) SIG_NAME M_G_MA<13>
J 0
(-1315 4035);
DISPLAY 0.659574 (-1315 4035);
PAINT MONO (-1315 4035);
DISPLAY INVISIBLE (-1315 4035);
FORCEPROP 1 LASTPIN (-1325 4025) BN 13
J 0
(-1375 4035);
DISPLAY 0.617021 (-1375 4035);
PAINT PINK (-1375 4035);
FORCEPROP 2 LAST CDS_LIB mstr_standard
J 2
(-1375 4025);
DISPLAY 0.787234 (-1375 4025);
PAINT MONO (-1375 4025);
DISPLAY INVISIBLE (-1375 4025);
FORCEPROP 1 LAST BODY_TYPE PLUMBING
J 0
(-1375 3975);
DISPLAY 1.234043 (-1375 3975);
PAINT GREEN (-1375 3975);
DISPLAY INVISIBLE (-1375 3975);
FORCEPROP 1 LAST HDL_TAP TRUE
J 0
(-1050 3900);
DISPLAY 1.234043 (-1050 3900);
PAINT GREEN (-1050 3900);
DISPLAY INVISIBLE (-1050 3900);
FORCEPROP 1 LAST PATH I126
J 0
(-1377 4025);
DISPLAY 0.872340 (-1377 4025);
PAINT GREEN (-1377 4025);
DISPLAY INVISIBLE (-1377 4025);
FORCEADD TAP..6
(-1375 4225);
FORCEPROP 3 LASTPIN (-1325 4225) SIG_NAME M_G_MA<17>
J 0
(-1315 4235);
DISPLAY 0.659574 (-1315 4235);
PAINT MONO (-1315 4235);
DISPLAY INVISIBLE (-1315 4235);
FORCEPROP 1 LASTPIN (-1325 4225) BN 17
J 0
(-1375 4235);
DISPLAY 0.617021 (-1375 4235);
PAINT PINK (-1375 4235);
FORCEPROP 2 LAST CDS_LIB mstr_standard
J 0
(-1375 4225);
DISPLAY 0.787234 (-1375 4225);
PAINT MONO (-1375 4225);
DISPLAY INVISIBLE (-1375 4225);
FORCEPROP 1 LAST BODY_TYPE PLUMBING
J 0
(-1375 4175);
DISPLAY 1.234043 (-1375 4175);
PAINT GREEN (-1375 4175);
DISPLAY INVISIBLE (-1375 4175);
FORCEPROP 1 LAST HDL_TAP TRUE
J 0
(-1050 4100);
DISPLAY 1.234043 (-1050 4100);
PAINT GREEN (-1050 4100);
DISPLAY INVISIBLE (-1050 4100);
FORCEPROP 1 LAST PATH I127
J 0
(-1377 4225);
DISPLAY 0.872340 (-1377 4225);
PAINT GREEN (-1377 4225);
DISPLAY INVISIBLE (-1377 4225);
FORCEADD TAP..6
(-1375 4175);
FORCEPROP 3 LASTPIN (-1325 4175) SIG_NAME M_G_MA<16>
J 0
(-1315 4185);
DISPLAY 0.659574 (-1315 4185);
PAINT MONO (-1315 4185);
DISPLAY INVISIBLE (-1315 4185);
FORCEPROP 1 LASTPIN (-1325 4175) BN 16
J 0
(-1375 4185);
DISPLAY 0.617021 (-1375 4185);
PAINT PINK (-1375 4185);
FORCEPROP 2 LAST CDS_LIB mstr_standard
J 2
(-1375 4175);
DISPLAY 0.787234 (-1375 4175);
PAINT MONO (-1375 4175);
DISPLAY INVISIBLE (-1375 4175);
FORCEPROP 1 LAST BODY_TYPE PLUMBING
J 0
(-1375 4125);
DISPLAY 1.234043 (-1375 4125);
PAINT GREEN (-1375 4125);
DISPLAY INVISIBLE (-1375 4125);
FORCEPROP 1 LAST HDL_TAP TRUE
J 0
(-1050 4050);
DISPLAY 1.234043 (-1050 4050);
PAINT GREEN (-1050 4050);
DISPLAY INVISIBLE (-1050 4050);
FORCEPROP 1 LAST PATH I128
J 0
(-1377 4175);
DISPLAY 0.872340 (-1377 4175);
PAINT GREEN (-1377 4175);
DISPLAY INVISIBLE (-1377 4175);
FORCEADD SCONN288_H44441003..1
(-625 2575);
FORCEPROP 1 LAST PART_NUMBER H44441-003
J 0
(-1075 575);
DISPLAY 0.617021 (-1075 575);
PAINT BLUE (-1075 575);
FORCEPROP 2 LASTPIN (-1125 1075) $PN 146
J 2
(-1135 1085);
DISPLAY 0.617021 (-1135 1085);
PAINT ORANGE (-1135 1085);
FORCEPROP 2 LASTPIN (-1125 1425) $PN 284
J 2
(-1135 1435);
DISPLAY 0.617021 (-1135 1435);
PAINT ORANGE (-1135 1435);
FORCEPROP 2 LASTPIN (-1125 1225) $PN 285
J 2
(-1135 1235);
DISPLAY 0.617021 (-1135 1235);
PAINT ORANGE (-1135 1235);
FORCEPROP 2 LASTPIN (-1125 1175) $PN 141
J 2
(-1135 1185);
DISPLAY 0.617021 (-1135 1185);
PAINT ORANGE (-1135 1185);
FORCEPROP 2 LASTPIN (-1125 775) $PN 230
J 2
(-1135 785);
DISPLAY 0.617021 (-1135 785);
PAINT ORANGE (-1135 785);
FORCEPROP 2 LASTPIN (-1125 1375) $PN 238
J 2
(-1135 1385);
DISPLAY 0.617021 (-1135 1385);
PAINT ORANGE (-1135 1385);
FORCEPROP 2 LASTPIN (-1125 1325) $PN 140
J 2
(-1135 1335);
DISPLAY 0.617021 (-1135 1335);
PAINT ORANGE (-1135 1335);
FORCEPROP 2 LASTPIN (-1125 1275) $PN 139
J 2
(-1135 1285);
DISPLAY 0.617021 (-1135 1285);
PAINT ORANGE (-1135 1285);
FORCEPROP 2 LASTPIN (-1125 2725) $PN 237
J 2
(-1135 2735);
DISPLAY 0.617021 (-1135 2735);
PAINT ORANGE (-1135 2735);
FORCEPROP 2 LASTPIN (-1125 2675) $PN 93
J 2
(-1135 2685);
DISPLAY 0.617021 (-1135 2685);
PAINT ORANGE (-1135 2685);
FORCEPROP 2 LASTPIN (-1125 2625) $PN 89
J 2
(-1135 2635);
DISPLAY 0.617021 (-1135 2635);
PAINT ORANGE (-1135 2635);
FORCEPROP 2 LASTPIN (-1125 2575) $PN 84
J 2
(-1135 2585);
DISPLAY 0.617021 (-1135 2585);
PAINT ORANGE (-1135 2585);
FORCEPROP 2 LASTPIN (-1125 975) $PN 144
J 2
(-1135 985);
DISPLAY 0.617021 (-1135 985);
PAINT ORANGE (-1135 985);
FORCEPROP 2 LASTPIN (-1125 925) $PN 227
J 2
(-1135 935);
DISPLAY 0.617021 (-1135 935);
PAINT ORANGE (-1135 935);
FORCEPROP 2 LASTPIN (-1125 875) $PN 205
J 2
(-1135 885);
DISPLAY 0.617021 (-1135 885);
PAINT ORANGE (-1135 885);
FORCEPROP 2 LASTPIN (-1125 1675) $PN 58
J 2
(-1135 1685);
DISPLAY 0.617021 (-1135 1685);
PAINT ORANGE (-1135 1685);
FORCEPROP 2 LASTPIN (-1125 1725) $PN 222
J 2
(-1135 1735);
DISPLAY 0.617021 (-1135 1735);
PAINT ORANGE (-1135 1735);
FORCEPROP 2 LASTPIN (-1125 2325) $PN 91
J 2
(-1135 2335);
DISPLAY 0.617021 (-1135 2335);
PAINT ORANGE (-1135 2335);
FORCEPROP 2 LASTPIN (-1125 2275) $PN 87
J 2
(-1135 2285);
DISPLAY 0.617021 (-1135 2285);
PAINT ORANGE (-1135 2285);
FORCEPROP 2 LASTPIN (-1125 1625) $PN 78
J 2
(-1135 1635);
DISPLAY 0.617021 (-1135 1635);
PAINT ORANGE (-1135 1635);
FORCEPROP 2 LASTPIN (-125 4225) $PN 280
J 0
(-115 4235);
DISPLAY 0.617021 (-115 4235);
PAINT ORANGE (-115 4235);
FORCEPROP 2 LASTPIN (-125 4175) $PN 135
J 0
(-115 4185);
DISPLAY 0.617021 (-115 4185);
PAINT ORANGE (-115 4185);
FORCEPROP 2 LASTPIN (-125 4125) $PN 273
J 0
(-115 4135);
DISPLAY 0.617021 (-115 4135);
PAINT ORANGE (-115 4135);
FORCEPROP 2 LASTPIN (-125 4075) $PN 128
J 0
(-115 4085);
DISPLAY 0.617021 (-115 4085);
PAINT ORANGE (-115 4085);
FORCEPROP 2 LASTPIN (-125 4025) $PN 282
J 0
(-115 4035);
DISPLAY 0.617021 (-115 4035);
PAINT ORANGE (-115 4035);
FORCEPROP 2 LASTPIN (-125 3975) $PN 137
J 0
(-115 3985);
DISPLAY 0.617021 (-115 3985);
PAINT ORANGE (-115 3985);
FORCEPROP 2 LASTPIN (-125 3925) $PN 275
J 0
(-115 3935);
DISPLAY 0.617021 (-115 3935);
PAINT ORANGE (-115 3935);
FORCEPROP 2 LASTPIN (-125 3875) $PN 130
J 0
(-115 3885);
DISPLAY 0.617021 (-115 3885);
PAINT ORANGE (-115 3885);
FORCEPROP 2 LASTPIN (-125 3825) $PN 269
J 0
(-115 3835);
DISPLAY 0.617021 (-115 3835);
PAINT ORANGE (-115 3835);
FORCEPROP 2 LASTPIN (-125 3775) $PN 124
J 0
(-115 3785);
DISPLAY 0.617021 (-115 3785);
PAINT ORANGE (-115 3785);
FORCEPROP 2 LASTPIN (-125 3725) $PN 262
J 0
(-115 3735);
DISPLAY 0.617021 (-115 3735);
PAINT ORANGE (-115 3735);
FORCEPROP 2 LASTPIN (-125 3675) $PN 117
J 0
(-115 3685);
DISPLAY 0.617021 (-115 3685);
PAINT ORANGE (-115 3685);
FORCEPROP 2 LASTPIN (-125 3625) $PN 271
J 0
(-115 3635);
DISPLAY 0.617021 (-115 3635);
PAINT ORANGE (-115 3635);
FORCEPROP 2 LASTPIN (-125 3575) $PN 126
J 0
(-115 3585);
DISPLAY 0.617021 (-115 3585);
PAINT ORANGE (-115 3585);
FORCEPROP 2 LASTPIN (-125 3525) $PN 264
J 0
(-115 3535);
DISPLAY 0.617021 (-115 3535);
PAINT ORANGE (-115 3535);
FORCEPROP 2 LASTPIN (-125 3475) $PN 119
J 0
(-115 3485);
DISPLAY 0.617021 (-115 3485);
PAINT ORANGE (-115 3485);
FORCEPROP 2 LASTPIN (-125 3425) $PN 258
J 0
(-115 3435);
DISPLAY 0.617021 (-115 3435);
PAINT ORANGE (-115 3435);
FORCEPROP 2 LASTPIN (-125 3375) $PN 113
J 0
(-115 3385);
DISPLAY 0.617021 (-115 3385);
PAINT ORANGE (-115 3385);
FORCEPROP 2 LASTPIN (-125 3325) $PN 251
J 0
(-115 3335);
DISPLAY 0.617021 (-115 3335);
PAINT ORANGE (-115 3335);
FORCEPROP 2 LASTPIN (-125 3275) $PN 106
J 0
(-115 3285);
DISPLAY 0.617021 (-115 3285);
PAINT ORANGE (-115 3285);
FORCEPROP 2 LASTPIN (-125 3225) $PN 260
J 0
(-115 3235);
DISPLAY 0.617021 (-115 3235);
PAINT ORANGE (-115 3235);
FORCEPROP 2 LASTPIN (-125 3125) $PN 253
J 0
(-115 3135);
DISPLAY 0.617021 (-115 3135);
PAINT ORANGE (-115 3135);
FORCEPROP 2 LASTPIN (-125 3075) $PN 108
J 0
(-115 3085);
DISPLAY 0.617021 (-115 3085);
PAINT ORANGE (-115 3085);
FORCEPROP 2 LASTPIN (-125 3025) $PN 247
J 0
(-115 3035);
DISPLAY 0.617021 (-115 3035);
PAINT ORANGE (-115 3035);
FORCEPROP 2 LASTPIN (-125 2975) $PN 102
J 0
(-115 2985);
DISPLAY 0.617021 (-115 2985);
PAINT ORANGE (-115 2985);
FORCEPROP 2 LASTPIN (-125 2925) $PN 240
J 0
(-115 2935);
DISPLAY 0.617021 (-115 2935);
PAINT ORANGE (-115 2935);
FORCEPROP 2 LASTPIN (-125 2875) $PN 95
J 0
(-115 2885);
DISPLAY 0.617021 (-115 2885);
PAINT ORANGE (-115 2885);
FORCEPROP 2 LASTPIN (-125 2825) $PN 249
J 0
(-115 2835);
DISPLAY 0.617021 (-115 2835);
PAINT ORANGE (-115 2835);
FORCEPROP 2 LASTPIN (-125 2775) $PN 104
J 0
(-115 2785);
DISPLAY 0.617021 (-115 2785);
PAINT ORANGE (-115 2785);
FORCEPROP 2 LASTPIN (-125 2725) $PN 242
J 0
(-115 2735);
DISPLAY 0.617021 (-115 2735);
PAINT ORANGE (-115 2735);
FORCEPROP 2 LASTPIN (-125 2675) $PN 97
J 0
(-115 2685);
DISPLAY 0.617021 (-115 2685);
PAINT ORANGE (-115 2685);
FORCEPROP 2 LASTPIN (-125 2625) $PN 188
J 0
(-115 2635);
DISPLAY 0.617021 (-115 2635);
PAINT ORANGE (-115 2635);
FORCEPROP 2 LASTPIN (-125 2575) $PN 43
J 0
(-115 2585);
DISPLAY 0.617021 (-115 2585);
PAINT ORANGE (-115 2585);
FORCEPROP 2 LASTPIN (-125 2525) $PN 181
J 0
(-115 2535);
DISPLAY 0.617021 (-115 2535);
PAINT ORANGE (-115 2535);
FORCEPROP 2 LASTPIN (-125 2475) $PN 36
J 0
(-115 2485);
DISPLAY 0.617021 (-115 2485);
PAINT ORANGE (-115 2485);
FORCEPROP 2 LASTPIN (-125 2425) $PN 190
J 0
(-115 2435);
DISPLAY 0.617021 (-115 2435);
PAINT ORANGE (-115 2435);
FORCEPROP 2 LASTPIN (-125 2375) $PN 45
J 0
(-115 2385);
DISPLAY 0.617021 (-115 2385);
PAINT ORANGE (-115 2385);
FORCEPROP 2 LASTPIN (-125 2325) $PN 183
J 0
(-115 2335);
DISPLAY 0.617021 (-115 2335);
PAINT ORANGE (-115 2335);
FORCEPROP 2 LASTPIN (-125 2275) $PN 38
J 0
(-115 2285);
DISPLAY 0.617021 (-115 2285);
PAINT ORANGE (-115 2285);
FORCEPROP 2 LASTPIN (-125 2225) $PN 177
J 0
(-115 2235);
DISPLAY 0.617021 (-115 2235);
PAINT ORANGE (-115 2235);
FORCEPROP 2 LASTPIN (-125 2175) $PN 32
J 0
(-115 2185);
DISPLAY 0.617021 (-115 2185);
PAINT ORANGE (-115 2185);
FORCEPROP 2 LASTPIN (-125 2125) $PN 170
J 0
(-115 2135);
DISPLAY 0.617021 (-115 2135);
PAINT ORANGE (-115 2135);
FORCEPROP 2 LASTPIN (-125 2075) $PN 25
J 0
(-115 2085);
DISPLAY 0.617021 (-115 2085);
PAINT ORANGE (-115 2085);
FORCEPROP 2 LASTPIN (-125 2025) $PN 179
J 0
(-115 2035);
DISPLAY 0.617021 (-115 2035);
PAINT ORANGE (-115 2035);
FORCEPROP 2 LASTPIN (-125 1975) $PN 34
J 0
(-115 1985);
DISPLAY 0.617021 (-115 1985);
PAINT ORANGE (-115 1985);
FORCEPROP 2 LASTPIN (-125 1925) $PN 172
J 0
(-115 1935);
DISPLAY 0.617021 (-115 1935);
PAINT ORANGE (-115 1935);
FORCEPROP 2 LASTPIN (-125 1875) $PN 27
J 0
(-115 1885);
DISPLAY 0.617021 (-115 1885);
PAINT ORANGE (-115 1885);
FORCEPROP 2 LASTPIN (-125 1825) $PN 166
J 0
(-115 1835);
DISPLAY 0.617021 (-115 1835);
PAINT ORANGE (-115 1835);
FORCEPROP 2 LASTPIN (-125 1775) $PN 21
J 0
(-115 1785);
DISPLAY 0.617021 (-115 1785);
PAINT ORANGE (-115 1785);
FORCEPROP 2 LASTPIN (-125 1725) $PN 159
J 0
(-115 1735);
DISPLAY 0.617021 (-115 1735);
PAINT ORANGE (-115 1735);
FORCEPROP 2 LASTPIN (-125 1675) $PN 14
J 0
(-115 1685);
DISPLAY 0.617021 (-115 1685);
PAINT ORANGE (-115 1685);
FORCEPROP 2 LASTPIN (-125 1625) $PN 168
J 0
(-115 1635);
DISPLAY 0.617021 (-115 1635);
PAINT ORANGE (-115 1635);
FORCEPROP 2 LASTPIN (-125 1575) $PN 23
J 0
(-115 1585);
DISPLAY 0.617021 (-115 1585);
PAINT ORANGE (-115 1585);
FORCEPROP 2 LASTPIN (-125 1525) $PN 161
J 0
(-115 1535);
DISPLAY 0.617021 (-115 1535);
PAINT ORANGE (-115 1535);
FORCEPROP 2 LASTPIN (-125 1475) $PN 16
J 0
(-115 1485);
DISPLAY 0.617021 (-115 1485);
PAINT ORANGE (-115 1485);
FORCEPROP 2 LASTPIN (-125 1425) $PN 155
J 0
(-115 1435);
DISPLAY 0.617021 (-115 1435);
PAINT ORANGE (-115 1435);
FORCEPROP 2 LASTPIN (-125 1375) $PN 10
J 0
(-115 1385);
DISPLAY 0.617021 (-115 1385);
PAINT ORANGE (-115 1385);
FORCEPROP 2 LASTPIN (-125 1325) $PN 148
J 0
(-115 1335);
DISPLAY 0.617021 (-115 1335);
PAINT ORANGE (-115 1335);
FORCEPROP 2 LASTPIN (-125 1275) $PN 3
J 0
(-115 1285);
DISPLAY 0.617021 (-115 1285);
PAINT ORANGE (-115 1285);
FORCEPROP 2 LASTPIN (-125 1225) $PN 157
J 0
(-115 1235);
DISPLAY 0.617021 (-115 1235);
PAINT ORANGE (-115 1235);
FORCEPROP 2 LASTPIN (-125 1175) $PN 12
J 0
(-115 1185);
DISPLAY 0.617021 (-115 1185);
PAINT ORANGE (-115 1185);
FORCEPROP 2 LASTPIN (-125 1125) $PN 150
J 0
(-115 1135);
DISPLAY 0.617021 (-115 1135);
PAINT ORANGE (-115 1135);
FORCEPROP 2 LASTPIN (-125 1075) $PN 5
J 0
(-115 1085);
DISPLAY 0.617021 (-115 1085);
PAINT ORANGE (-115 1085);
FORCEPROP 2 LASTPIN (-1125 2475) $PN 203
J 2
(-1135 2485);
DISPLAY 0.617021 (-1135 2485);
PAINT ORANGE (-1135 2485);
FORCEPROP 2 LASTPIN (-1125 2425) $PN 60
J 2
(-1135 2435);
DISPLAY 0.617021 (-1135 2435);
PAINT ORANGE (-1135 2435);
FORCEPROP 2 LASTPIN (-1125 3025) $PN 218
J 2
(-1135 3035);
DISPLAY 0.617021 (-1135 3035);
PAINT ORANGE (-1135 3035);
FORCEPROP 2 LASTPIN (-1125 2975) $PN 219
J 2
(-1135 2985);
DISPLAY 0.617021 (-1135 2985);
PAINT ORANGE (-1135 2985);
FORCEPROP 2 LASTPIN (-1125 2925) $PN 74
J 2
(-1135 2935);
DISPLAY 0.617021 (-1135 2935);
PAINT ORANGE (-1135 2935);
FORCEPROP 2 LASTPIN (-1125 2875) $PN 75
J 2
(-1135 2885);
DISPLAY 0.617021 (-1135 2885);
PAINT ORANGE (-1135 2885);
FORCEPROP 2 LASTPIN (-1125 2175) $PN 199
J 2
(-1135 2185);
DISPLAY 0.617021 (-1135 2185);
PAINT ORANGE (-1135 2185);
FORCEPROP 2 LASTPIN (-1125 2125) $PN 54
J 2
(-1135 2135);
DISPLAY 0.617021 (-1135 2135);
PAINT ORANGE (-1135 2135);
FORCEPROP 2 LASTPIN (-1125 2075) $PN 192
J 2
(-1135 2085);
DISPLAY 0.617021 (-1135 2085);
PAINT ORANGE (-1135 2085);
FORCEPROP 2 LASTPIN (-1125 2025) $PN 47
J 2
(-1135 2035);
DISPLAY 0.617021 (-1135 2035);
PAINT ORANGE (-1135 2035);
FORCEPROP 2 LASTPIN (-1125 1975) $PN 201
J 2
(-1135 1985);
DISPLAY 0.617021 (-1135 1985);
PAINT ORANGE (-1135 1985);
FORCEPROP 2 LASTPIN (-1125 1925) $PN 56
J 2
(-1135 1935);
DISPLAY 0.617021 (-1135 1935);
PAINT ORANGE (-1135 1935);
FORCEPROP 2 LASTPIN (-1125 1875) $PN 194
J 2
(-1135 1885);
DISPLAY 0.617021 (-1135 1885);
PAINT ORANGE (-1135 1885);
FORCEPROP 2 LASTPIN (-1125 1825) $PN 49
J 2
(-1135 1835);
DISPLAY 0.617021 (-1135 1835);
PAINT ORANGE (-1135 1835);
FORCEPROP 2 LASTPIN (-1125 2775) $PN 235
J 2
(-1135 2785);
DISPLAY 0.617021 (-1135 2785);
PAINT ORANGE (-1135 2785);
FORCEPROP 2 LASTPIN (-1125 3175) $PN 207
J 2
(-1135 3185);
DISPLAY 0.617021 (-1135 3185);
PAINT ORANGE (-1135 3185);
FORCEPROP 2 LASTPIN (-1125 3125) $PN 63
J 2
(-1135 3135);
DISPLAY 0.617021 (-1135 3135);
PAINT ORANGE (-1135 3135);
FORCEPROP 2 LASTPIN (-1125 3275) $PN 224
J 2
(-1135 3285);
DISPLAY 0.617021 (-1135 3285);
PAINT ORANGE (-1135 3285);
FORCEPROP 2 LASTPIN (-1125 3225) $PN 81
J 2
(-1135 3235);
DISPLAY 0.617021 (-1135 3235);
PAINT ORANGE (-1135 3235);
FORCEPROP 2 LASTPIN (-1125 1575) $PN 208
J 2
(-1135 1585);
DISPLAY 0.617021 (-1135 1585);
PAINT ORANGE (-1135 1585);
FORCEPROP 2 LASTPIN (-1125 1525) $PN 62
J 2
(-1135 1535);
DISPLAY 0.617021 (-1135 1535);
PAINT ORANGE (-1135 1535);
FORCEPROP 2 LASTPIN (-1125 4225) $PN 234
J 2
(-1135 4235);
DISPLAY 0.617021 (-1135 4235);
PAINT ORANGE (-1135 4235);
FORCEPROP 2 LASTPIN (-1125 4175) $PN 82
J 2
(-1135 4185);
DISPLAY 0.617021 (-1135 4185);
PAINT ORANGE (-1135 4185);
FORCEPROP 2 LASTPIN (-1125 4075) $PN 228
J 2
(-1135 4085);
DISPLAY 0.617021 (-1135 4085);
PAINT ORANGE (-1135 4085);
FORCEPROP 2 LASTPIN (-1125 4025) $PN 232
J 2
(-1135 4035);
DISPLAY 0.617021 (-1135 4035);
PAINT ORANGE (-1135 4035);
FORCEPROP 2 LASTPIN (-1125 3975) $PN 65
J 2
(-1135 3985);
DISPLAY 0.617021 (-1135 3985);
PAINT ORANGE (-1135 3985);
FORCEPROP 2 LASTPIN (-1125 3925) $PN 210
J 2
(-1135 3935);
DISPLAY 0.617021 (-1135 3935);
PAINT ORANGE (-1135 3935);
FORCEPROP 2 LASTPIN (-1125 3875) $PN 225
J 2
(-1135 3885);
DISPLAY 0.617021 (-1135 3885);
PAINT ORANGE (-1135 3885);
FORCEPROP 2 LASTPIN (-1125 3825) $PN 66
J 2
(-1135 3835);
DISPLAY 0.617021 (-1135 3835);
PAINT ORANGE (-1135 3835);
FORCEPROP 2 LASTPIN (-1125 3775) $PN 68
J 2
(-1135 3785);
DISPLAY 0.617021 (-1135 3785);
PAINT ORANGE (-1135 3785);
FORCEPROP 2 LASTPIN (-1125 3725) $PN 211
J 2
(-1135 3735);
DISPLAY 0.617021 (-1135 3735);
PAINT ORANGE (-1135 3735);
FORCEPROP 2 LASTPIN (-1125 3675) $PN 69
J 2
(-1135 3685);
DISPLAY 0.617021 (-1135 3685);
PAINT ORANGE (-1135 3685);
FORCEPROP 2 LASTPIN (-1125 3625) $PN 213
J 2
(-1135 3635);
DISPLAY 0.617021 (-1135 3635);
PAINT ORANGE (-1135 3635);
FORCEPROP 2 LASTPIN (-1125 3575) $PN 214
J 2
(-1135 3585);
DISPLAY 0.617021 (-1135 3585);
PAINT ORANGE (-1135 3585);
FORCEPROP 2 LASTPIN (-1125 3525) $PN 71
J 2
(-1135 3535);
DISPLAY 0.617021 (-1135 3535);
PAINT ORANGE (-1135 3535);
FORCEPROP 2 LASTPIN (-1125 3475) $PN 216
J 2
(-1135 3485);
DISPLAY 0.617021 (-1135 3485);
PAINT ORANGE (-1135 3485);
FORCEPROP 2 LASTPIN (-1125 3425) $PN 72
J 2
(-1135 3435);
DISPLAY 0.617021 (-1135 3435);
PAINT ORANGE (-1135 3435);
FORCEPROP 2 LASTPIN (-1125 3375) $PN 79
J 2
(-1135 3385);
DISPLAY 0.617021 (-1135 3385);
PAINT ORANGE (-1135 3385);
FORCEPROP 1 LAST LOCATION J9T1
J 0
(-1075 4475);
DISPLAY 0.617021 (-1075 4475);
PAINT AQUA (-1075 4475);
FORCEPROP 2 LASTPIN (-1125 4125) $PN 86
J 2
(-1135 4135);
DISPLAY 0.617021 (-1135 4135);
PAINT ORANGE (-1135 4135);
FORCEPROP 1 LAST MATERIAL SCONN
J 0
(-1075 4425);
DISPLAY 0.617021 (-1075 4425);
PAINT SKYBLUE (-1075 4425);
FORCEPROP 2 LASTPIN (-125 3175) $PN 115
J 0
(-115 3185);
DISPLAY 0.617021 (-115 3185);
PAINT ORANGE (-115 3185);
FORCEPROP 0 LAST BOM_SS NOPOP
J 0
(-848 4541);
DISPLAY 1.021277 (-848 4541);
PAINT BROWN (-848 4541);
DISPLAY BOTH (-848 4541);
FORCEPROP 1 LAST PACK_TYPE PIP
J 0
(-1075 4525);
PAINT SKYBLUE (-1075 4525);
DISPLAY INVISIBLE (-1075 4525);
FORCEPROP 2 LAST BOM_COST MEM
J 0
(-625 2575);
PAINT ORANGE (-625 2575);
DISPLAY INVISIBLE (-625 2575);
FORCEPROP 2 LAST CDS_LIB mstr_sconn
J 0
(-625 2575);
PAINT ORANGE (-625 2575);
DISPLAY INVISIBLE (-625 2575);
FORCEPROP 2 LAST SEC_TYPE PIP
J 0
(-1075 4525);
DISPLAY 1.021277 (-1075 4525);
PAINT ORANGE (-1075 4525);
DISPLAY INVISIBLE (-1075 4525);
FORCEPROP 2 LAST SEC 1
J 0
(-1075 4525);
DISPLAY 0.680851 (-1075 4525);
PAINT MONO (-1075 4525);
DISPLAY INVISIBLE (-1075 4525);
FORCEPROP 2 LAST CDS_LOCATION J9T1
J 0
(-1075 4475);
DISPLAY 0.617021 (-1075 4475);
PAINT AQUA (-1075 4475);
DISPLAY INVISIBLE (-1075 4475);
FORCEPROP 1 LAST PATH I13
J 0
(-625 4425);
PAINT GREEN (-625 4425);
DISPLAY INVISIBLE (-625 4425);
FORCEPROP 2 LAST ROOM DDR4_GH_G
J 0
(-625 2575);
PAINT ORANGE (-625 2575);
DISPLAY INVISIBLE (-625 2575);
FORCEADD TAP..6
R 2
(125 3975);
FORCEPROP 3 LASTPIN (75 3975) SIG_NAME M_G_DQ<58>
J 0
(85 3985);
DISPLAY 0.659574 (85 3985);
PAINT MONO (85 3985);
DISPLAY INVISIBLE (85 3985);
FORCEPROP 1 LASTPIN (75 3975) BN 58
J 2
(125 3985);
DISPLAY 0.617021 (125 3985);
PAINT PINK (125 3985);
FORCEPROP 2 LAST CDS_LIB mstr_standard
J 2
(125 3975);
DISPLAY 0.787234 (125 3975);
PAINT MONO (125 3975);
DISPLAY INVISIBLE (125 3975);
FORCEPROP 1 LAST BODY_TYPE PLUMBING
J 2
(125 3925);
DISPLAY 1.234043 (125 3925);
PAINT GREEN (125 3925);
DISPLAY INVISIBLE (125 3925);
FORCEPROP 1 LAST HDL_TAP TRUE
J 2
(-200 3850);
DISPLAY 1.234043 (-200 3850);
PAINT GREEN (-200 3850);
DISPLAY INVISIBLE (-200 3850);
FORCEPROP 1 LAST PATH I135
J 2
(127 3975);
DISPLAY 0.872340 (127 3975);
PAINT GREEN (127 3975);
DISPLAY INVISIBLE (127 3975);
FORCEADD TAP..6
R 2
(125 3925);
FORCEPROP 3 LASTPIN (75 3925) SIG_NAME M_G_DQ<57>
J 0
(85 3935);
DISPLAY 0.659574 (85 3935);
PAINT MONO (85 3935);
DISPLAY INVISIBLE (85 3935);
FORCEPROP 1 LASTPIN (75 3925) BN 57
J 2
(125 3935);
DISPLAY 0.617021 (125 3935);
PAINT PINK (125 3935);
FORCEPROP 2 LAST CDS_LIB mstr_standard
J 2
(125 3925);
DISPLAY 0.787234 (125 3925);
PAINT MONO (125 3925);
DISPLAY INVISIBLE (125 3925);
FORCEPROP 1 LAST BODY_TYPE PLUMBING
J 2
(125 3875);
DISPLAY 1.234043 (125 3875);
PAINT GREEN (125 3875);
DISPLAY INVISIBLE (125 3875);
FORCEPROP 1 LAST HDL_TAP TRUE
J 2
(-200 3800);
DISPLAY 1.234043 (-200 3800);
PAINT GREEN (-200 3800);
DISPLAY INVISIBLE (-200 3800);
FORCEPROP 1 LAST PATH I136
J 2
(127 3925);
DISPLAY 0.872340 (127 3925);
PAINT GREEN (127 3925);
DISPLAY INVISIBLE (127 3925);
FORCEADD TAP..6
R 2
(125 4025);
FORCEPROP 3 LASTPIN (75 4025) SIG_NAME M_G_DQ<59>
J 0
(85 4035);
DISPLAY 0.659574 (85 4035);
PAINT MONO (85 4035);
DISPLAY INVISIBLE (85 4035);
FORCEPROP 1 LASTPIN (75 4025) BN 59
J 2
(125 4035);
DISPLAY 0.617021 (125 4035);
PAINT PINK (125 4035);
FORCEPROP 2 LAST CDS_LIB mstr_standard
J 2
(125 4025);
DISPLAY 0.787234 (125 4025);
PAINT MONO (125 4025);
DISPLAY INVISIBLE (125 4025);
FORCEPROP 1 LAST BODY_TYPE PLUMBING
J 2
(125 3975);
DISPLAY 1.234043 (125 3975);
PAINT GREEN (125 3975);
DISPLAY INVISIBLE (125 3975);
FORCEPROP 1 LAST HDL_TAP TRUE
J 2
(-200 3900);
DISPLAY 1.234043 (-200 3900);
PAINT GREEN (-200 3900);
DISPLAY INVISIBLE (-200 3900);
FORCEPROP 1 LAST PATH I137
J 2
(127 4025);
DISPLAY 0.872340 (127 4025);
PAINT GREEN (127 4025);
DISPLAY INVISIBLE (127 4025);
FORCEADD TAP..6
R 2
(125 4125);
FORCEPROP 3 LASTPIN (75 4125) SIG_NAME M_G_DQ<61>
J 0
(85 4135);
DISPLAY 0.659574 (85 4135);
PAINT MONO (85 4135);
DISPLAY INVISIBLE (85 4135);
FORCEPROP 1 LASTPIN (75 4125) BN 61
J 2
(125 4135);
DISPLAY 0.617021 (125 4135);
PAINT PINK (125 4135);
FORCEPROP 2 LAST CDS_LIB mstr_standard
J 2
(125 4125);
DISPLAY 0.787234 (125 4125);
PAINT MONO (125 4125);
DISPLAY INVISIBLE (125 4125);
FORCEPROP 1 LAST BODY_TYPE PLUMBING
J 2
(125 4075);
DISPLAY 1.234043 (125 4075);
PAINT GREEN (125 4075);
DISPLAY INVISIBLE (125 4075);
FORCEPROP 1 LAST HDL_TAP TRUE
J 2
(-200 4000);
DISPLAY 1.234043 (-200 4000);
PAINT GREEN (-200 4000);
DISPLAY INVISIBLE (-200 4000);
FORCEPROP 1 LAST PATH I138
J 2
(127 4125);
DISPLAY 0.872340 (127 4125);
PAINT GREEN (127 4125);
DISPLAY INVISIBLE (127 4125);
FORCEADD TAP..6
R 2
(125 4075);
FORCEPROP 3 LASTPIN (75 4075) SIG_NAME M_G_DQ<60>
J 0
(85 4085);
DISPLAY 0.659574 (85 4085);
PAINT MONO (85 4085);
DISPLAY INVISIBLE (85 4085);
FORCEPROP 1 LASTPIN (75 4075) BN 60
J 2
(125 4085);
DISPLAY 0.617021 (125 4085);
PAINT PINK (125 4085);
FORCEPROP 2 LAST CDS_LIB mstr_standard
J 2
(125 4075);
DISPLAY 0.787234 (125 4075);
PAINT MONO (125 4075);
DISPLAY INVISIBLE (125 4075);
FORCEPROP 1 LAST BODY_TYPE PLUMBING
J 2
(125 4025);
DISPLAY 1.234043 (125 4025);
PAINT GREEN (125 4025);
DISPLAY INVISIBLE (125 4025);
FORCEPROP 1 LAST HDL_TAP TRUE
J 2
(-200 3950);
DISPLAY 1.234043 (-200 3950);
PAINT GREEN (-200 3950);
DISPLAY INVISIBLE (-200 3950);
FORCEPROP 1 LAST PATH I139
J 2
(127 4075);
DISPLAY 0.872340 (127 4075);
PAINT GREEN (127 4075);
DISPLAY INVISIBLE (127 4075);
FORCEADD OFFPAGE..1
(-2025 2125);
FORCEPROP 2 LAST $XR5 82 
J 0
(-2696 2125);
DISPLAY 0.638298 (-2696 2125);
PAINT MONO (-2696 2125);
FORCEPROP 2 LAST $XR4 81 
J 0
(-2606 2125);
DISPLAY 0.638298 (-2606 2125);
PAINT MONO (-2606 2125);
FORCEPROP 2 LAST $XR3 80 
J 0
(-2516 2125);
DISPLAY 0.638298 (-2516 2125);
PAINT MONO (-2516 2125);
FORCEPROP 2 LAST $XR2 79 
J 0
(-2426 2125);
DISPLAY 0.638298 (-2426 2125);
PAINT MONO (-2426 2125);
FORCEPROP 2 LAST $XR1 77 
J 0
(-2336 2125);
DISPLAY 0.638298 (-2336 2125);
PAINT MONO (-2336 2125);
FORCEPROP 2 LAST $XR0 55 
J 0
(-2246 2125);
DISPLAY 0.638298 (-2246 2125);
PAINT MONO (-2246 2125);
FORCEPROP 2 LAST CDS_LIB mstr_standard
J 0
(-2025 2125);
DISPLAY 0.787234 (-2025 2125);
PAINT MONO (-2025 2125);
DISPLAY INVISIBLE (-2025 2125);
FORCEPROP 1 LAST OFFPAGE TRUE
J 0
(-1700 2000);
DISPLAY 0.936170 (-1700 2000);
PAINT GREEN (-1700 2000);
DISPLAY INVISIBLE (-1700 2000);
FORCEPROP 1 LAST COMMENT_BODY TRUE
J 0
(-1900 2025);
DISPLAY 0.936170 (-1900 2025);
PAINT GREEN (-1900 2025);
DISPLAY INVISIBLE (-1900 2025);
FORCEPROP 2 LAST PATH I14
J 0
(-2225 2175);
DISPLAY 1.021277 (-2225 2175);
PAINT ORANGE (-2225 2175);
DISPLAY INVISIBLE (-2225 2175);
FORCEADD TAP..6
R 2
(125 4175);
FORCEPROP 3 LASTPIN (75 4175) SIG_NAME M_G_DQ<62>
J 0
(85 4185);
DISPLAY 0.659574 (85 4185);
PAINT MONO (85 4185);
DISPLAY INVISIBLE (85 4185);
FORCEPROP 1 LASTPIN (75 4175) BN 62
J 2
(125 4185);
DISPLAY 0.617021 (125 4185);
PAINT PINK (125 4185);
FORCEPROP 2 LAST CDS_LIB mstr_standard
J 2
(125 4175);
DISPLAY 0.787234 (125 4175);
PAINT MONO (125 4175);
DISPLAY INVISIBLE (125 4175);
FORCEPROP 1 LAST BODY_TYPE PLUMBING
J 2
(125 4125);
DISPLAY 1.234043 (125 4125);
PAINT GREEN (125 4125);
DISPLAY INVISIBLE (125 4125);
FORCEPROP 1 LAST HDL_TAP TRUE
J 2
(-200 4050);
DISPLAY 1.234043 (-200 4050);
PAINT GREEN (-200 4050);
DISPLAY INVISIBLE (-200 4050);
FORCEPROP 1 LAST PATH I140
J 2
(127 4175);
DISPLAY 0.872340 (127 4175);
PAINT GREEN (127 4175);
DISPLAY INVISIBLE (127 4175);
FORCEADD TAP..6
R 2
(125 4225);
FORCEPROP 3 LASTPIN (75 4225) SIG_NAME M_G_DQ<63>
J 0
(85 4235);
DISPLAY 0.659574 (85 4235);
PAINT MONO (85 4235);
DISPLAY INVISIBLE (85 4235);
FORCEPROP 1 LASTPIN (75 4225) BN 63
J 2
(125 4235);
DISPLAY 0.617021 (125 4235);
PAINT PINK (125 4235);
FORCEPROP 2 LAST CDS_LIB mstr_standard
J 2
(125 4225);
DISPLAY 0.787234 (125 4225);
PAINT MONO (125 4225);
DISPLAY INVISIBLE (125 4225);
FORCEPROP 1 LAST BODY_TYPE PLUMBING
J 2
(125 4175);
DISPLAY 1.234043 (125 4175);
PAINT GREEN (125 4175);
DISPLAY INVISIBLE (125 4175);
FORCEPROP 1 LAST HDL_TAP TRUE
J 2
(-200 4100);
DISPLAY 1.234043 (-200 4100);
PAINT GREEN (-200 4100);
DISPLAY INVISIBLE (-200 4100);
FORCEPROP 1 LAST PATH I141
J 2
(127 4225);
DISPLAY 0.872340 (127 4225);
PAINT GREEN (127 4225);
DISPLAY INVISIBLE (127 4225);
FORCEADD OFFPAGE..3
(675 4275);
FORCEPROP 2 LAST $XR1 77 
J 0
(979 4275);
DISPLAY 0.638298 (979 4275);
PAINT MONO (979 4275);
FORCEPROP 2 LAST $XR0 57 
J 0
(889 4275);
DISPLAY 0.638298 (889 4275);
PAINT MONO (889 4275);
FORCEPROP 2 LAST CDS_LIB mstr_standard
J 0
(675 4275);
DISPLAY 0.787234 (675 4275);
PAINT MONO (675 4275);
DISPLAY INVISIBLE (675 4275);
FORCEPROP 1 LAST OFFPAGE TRUE
J 0
(1000 4150);
DISPLAY 0.936170 (1000 4150);
PAINT GREEN (1000 4150);
DISPLAY INVISIBLE (1000 4150);
FORCEPROP 1 LAST COMMENT_BODY TRUE
J 0
(625 4175);
DISPLAY 0.936170 (625 4175);
PAINT GREEN (625 4175);
DISPLAY INVISIBLE (625 4175);
FORCEPROP 2 LAST PATH I142
J 0
(900 4325);
DISPLAY 1.021277 (900 4325);
PAINT ORANGE (900 4325);
DISPLAY INVISIBLE (900 4325);
FORCEADD GND..1
R 2
(2850 700);
FORCEPROP 3 LASTPIN (2850 750) SIG_NAME GND\g
J 0
(2860 760);
DISPLAY 0.659574 (2860 760);
PAINT MONO (2860 760);
DISPLAY INVISIBLE (2860 760);
FORCEPROP 1 LAST VOLTAGE 0.0V
J 2
(2895 657);
DISPLAY 0.340426 (2895 657);
PAINT SKYBLUE (2895 657);
DISPLAY INVISIBLE (2895 657);
FORCEPROP 1 LAST SIZE 1B
J 2
(2775 650);
DISPLAY 1.170213 (2775 650);
PAINT GREEN (2775 650);
DISPLAY INVISIBLE (2775 650);
FORCEPROP 2 LAST CDS_LIB mstr_symbols
J 0
(2850 700);
DISPLAY 0.787234 (2850 700);
PAINT MONO (2850 700);
DISPLAY INVISIBLE (2850 700);
FORCEPROP 2 LAST BOM_COST MEM
J 0
(2850 705);
PAINT ORANGE (2850 705);
DISPLAY INVISIBLE (2850 705);
FORCEPROP 1 LAST BODY_TYPE PLUMBING
J 2
(2895 657);
DISPLAY 0.340426 (2895 657);
PAINT GREEN (2895 657);
DISPLAY INVISIBLE (2895 657);
FORCEPROP 1 LAST PATH I143
J 2
(2775 700);
DISPLAY 0.872340 (2775 700);
PAINT AQUA (2775 700);
DISPLAY INVISIBLE (2775 700);
FORCEPROP 2 LAST ROOM DDR4_GH_G
J 0
(2850 705);
PAINT ORANGE (2850 705);
DISPLAY INVISIBLE (2850 705);
FORCEPROP 1 LAST HDL_POWER GND
J 2
(2850 850);
DISPLAY 0.553191 (2850 850);
PAINT GREEN (2850 850);
DISPLAY INVISIBLE (2850 850);
FORCEADD SCONN288_H44441003..3
(3550 2000);
FORCEPROP 1 LAST PART_NUMBER H44441-003
J 0
(3100 650);
DISPLAY 0.617021 (3100 650);
PAINT BLUE (3100 650);
FORCEPROP 2 LASTPIN (3050 3150) $PN 2
J 2
(3040 3160);
DISPLAY 0.617021 (3040 3160);
PAINT ORANGE (3040 3160);
FORCEPROP 2 LASTPIN (3050 3100) $PN 4
J 2
(3040 3110);
DISPLAY 0.617021 (3040 3110);
PAINT ORANGE (3040 3110);
FORCEPROP 2 LASTPIN (3050 3050) $PN 6
J 2
(3040 3060);
DISPLAY 0.617021 (3040 3060);
PAINT ORANGE (3040 3060);
FORCEPROP 2 LASTPIN (3050 3000) $PN 9
J 2
(3040 3010);
DISPLAY 0.617021 (3040 3010);
PAINT ORANGE (3040 3010);
FORCEPROP 2 LASTPIN (3050 2900) $PN 13
J 2
(3040 2910);
DISPLAY 0.617021 (3040 2910);
PAINT ORANGE (3040 2910);
FORCEPROP 2 LASTPIN (3050 2850) $PN 15
J 2
(3040 2860);
DISPLAY 0.617021 (3040 2860);
PAINT ORANGE (3040 2860);
FORCEPROP 2 LASTPIN (3050 2800) $PN 17
J 2
(3040 2810);
DISPLAY 0.617021 (3040 2810);
PAINT ORANGE (3040 2810);
FORCEPROP 2 LASTPIN (3050 2750) $PN 20
J 2
(3040 2760);
DISPLAY 0.617021 (3040 2760);
PAINT ORANGE (3040 2760);
FORCEPROP 2 LASTPIN (3050 2700) $PN 22
J 2
(3040 2710);
DISPLAY 0.617021 (3040 2710);
PAINT ORANGE (3040 2710);
FORCEPROP 2 LASTPIN (3050 2650) $PN 24
J 2
(3040 2660);
DISPLAY 0.617021 (3040 2660);
PAINT ORANGE (3040 2660);
FORCEPROP 2 LASTPIN (3050 2600) $PN 26
J 2
(3040 2610);
DISPLAY 0.617021 (3040 2610);
PAINT ORANGE (3040 2610);
FORCEPROP 2 LASTPIN (3050 2550) $PN 28
J 2
(3040 2560);
DISPLAY 0.617021 (3040 2560);
PAINT ORANGE (3040 2560);
FORCEPROP 2 LASTPIN (3050 2500) $PN 31
J 2
(3040 2510);
DISPLAY 0.617021 (3040 2510);
PAINT ORANGE (3040 2510);
FORCEPROP 2 LASTPIN (3050 2450) $PN 33
J 2
(3040 2460);
DISPLAY 0.617021 (3040 2460);
PAINT ORANGE (3040 2460);
FORCEPROP 2 LASTPIN (3050 2400) $PN 35
J 2
(3040 2410);
DISPLAY 0.617021 (3040 2410);
PAINT ORANGE (3040 2410);
FORCEPROP 2 LASTPIN (3050 2350) $PN 37
J 2
(3040 2360);
DISPLAY 0.617021 (3040 2360);
PAINT ORANGE (3040 2360);
FORCEPROP 2 LASTPIN (3050 2300) $PN 39
J 2
(3040 2310);
DISPLAY 0.617021 (3040 2310);
PAINT ORANGE (3040 2310);
FORCEPROP 2 LASTPIN (3050 2250) $PN 42
J 2
(3040 2260);
DISPLAY 0.617021 (3040 2260);
PAINT ORANGE (3040 2260);
FORCEPROP 2 LASTPIN (3050 2200) $PN 44
J 2
(3040 2210);
DISPLAY 0.617021 (3040 2210);
PAINT ORANGE (3040 2210);
FORCEPROP 2 LASTPIN (3050 2150) $PN 46
J 2
(3040 2160);
DISPLAY 0.617021 (3040 2160);
PAINT ORANGE (3040 2160);
FORCEPROP 2 LASTPIN (3050 2100) $PN 48
J 2
(3040 2110);
DISPLAY 0.617021 (3040 2110);
PAINT ORANGE (3040 2110);
FORCEPROP 2 LASTPIN (3050 2050) $PN 50
J 2
(3040 2060);
DISPLAY 0.617021 (3040 2060);
PAINT ORANGE (3040 2060);
FORCEPROP 2 LASTPIN (3050 2000) $PN 53
J 2
(3040 2010);
DISPLAY 0.617021 (3040 2010);
PAINT ORANGE (3040 2010);
FORCEPROP 2 LASTPIN (3050 1950) $PN 55
J 2
(3040 1960);
DISPLAY 0.617021 (3040 1960);
PAINT ORANGE (3040 1960);
FORCEPROP 2 LASTPIN (3050 1900) $PN 57
J 2
(3040 1910);
DISPLAY 0.617021 (3040 1910);
PAINT ORANGE (3040 1910);
FORCEPROP 2 LASTPIN (3050 1850) $PN 94
J 2
(3040 1860);
DISPLAY 0.617021 (3040 1860);
PAINT ORANGE (3040 1860);
FORCEPROP 2 LASTPIN (3050 1800) $PN 96
J 2
(3040 1810);
DISPLAY 0.617021 (3040 1810);
PAINT ORANGE (3040 1810);
FORCEPROP 2 LASTPIN (3050 1750) $PN 98
J 2
(3040 1760);
DISPLAY 0.617021 (3040 1760);
PAINT ORANGE (3040 1760);
FORCEPROP 2 LASTPIN (3050 1600) $PN 105
J 2
(3040 1610);
DISPLAY 0.617021 (3040 1610);
PAINT ORANGE (3040 1610);
FORCEPROP 2 LASTPIN (3050 1550) $PN 107
J 2
(3040 1560);
DISPLAY 0.617021 (3040 1560);
PAINT ORANGE (3040 1560);
FORCEPROP 2 LASTPIN (3050 1500) $PN 109
J 2
(3040 1510);
DISPLAY 0.617021 (3040 1510);
PAINT ORANGE (3040 1510);
FORCEPROP 2 LASTPIN (3050 1450) $PN 112
J 2
(3040 1460);
DISPLAY 0.617021 (3040 1460);
PAINT ORANGE (3040 1460);
FORCEPROP 2 LASTPIN (3050 1400) $PN 114
J 2
(3040 1410);
DISPLAY 0.617021 (3040 1410);
PAINT ORANGE (3040 1410);
FORCEPROP 2 LASTPIN (3050 1350) $PN 116
J 2
(3040 1360);
DISPLAY 0.617021 (3040 1360);
PAINT ORANGE (3040 1360);
FORCEPROP 2 LASTPIN (3050 1300) $PN 118
J 2
(3040 1310);
DISPLAY 0.617021 (3040 1310);
PAINT ORANGE (3040 1310);
FORCEPROP 2 LASTPIN (3050 1250) $PN 120
J 2
(3040 1260);
DISPLAY 0.617021 (3040 1260);
PAINT ORANGE (3040 1260);
FORCEPROP 2 LASTPIN (3050 1150) $PN 125
J 2
(3040 1160);
DISPLAY 0.617021 (3040 1160);
PAINT ORANGE (3040 1160);
FORCEPROP 2 LASTPIN (3050 1100) $PN 127
J 2
(3040 1110);
DISPLAY 0.617021 (3040 1110);
PAINT ORANGE (3040 1110);
FORCEPROP 2 LASTPIN (3050 1050) $PN 129
J 2
(3040 1060);
DISPLAY 0.617021 (3040 1060);
PAINT ORANGE (3040 1060);
FORCEPROP 2 LASTPIN (3050 1000) $PN 131
J 2
(3040 1010);
DISPLAY 0.617021 (3040 1010);
PAINT ORANGE (3040 1010);
FORCEPROP 2 LASTPIN (3050 950) $PN 134
J 2
(3040 960);
DISPLAY 0.617021 (3040 960);
PAINT ORANGE (3040 960);
FORCEPROP 2 LASTPIN (3050 900) $PN 136
J 2
(3040 910);
DISPLAY 0.617021 (3040 910);
PAINT ORANGE (3040 910);
FORCEPROP 2 LASTPIN (3050 850) $PN 138
J 2
(3040 860);
DISPLAY 0.617021 (3040 860);
PAINT ORANGE (3040 860);
FORCEPROP 2 LASTPIN (4050 3150) $PN 147
J 0
(4060 3160);
DISPLAY 0.617021 (4060 3160);
PAINT ORANGE (4060 3160);
FORCEPROP 2 LASTPIN (4050 3100) $PN 149
J 0
(4060 3110);
DISPLAY 0.617021 (4060 3110);
PAINT ORANGE (4060 3110);
FORCEPROP 2 LASTPIN (4050 3050) $PN 151
J 0
(4060 3060);
DISPLAY 0.617021 (4060 3060);
PAINT ORANGE (4060 3060);
FORCEPROP 2 LASTPIN (4050 3000) $PN 154
J 0
(4060 3010);
DISPLAY 0.617021 (4060 3010);
PAINT ORANGE (4060 3010);
FORCEPROP 2 LASTPIN (4050 2950) $PN 156
J 0
(4060 2960);
DISPLAY 0.617021 (4060 2960);
PAINT ORANGE (4060 2960);
FORCEPROP 2 LASTPIN (4050 2900) $PN 158
J 0
(4060 2910);
DISPLAY 0.617021 (4060 2910);
PAINT ORANGE (4060 2910);
FORCEPROP 2 LASTPIN (4050 2800) $PN 162
J 0
(4060 2810);
DISPLAY 0.617021 (4060 2810);
PAINT ORANGE (4060 2810);
FORCEPROP 2 LASTPIN (4050 2750) $PN 165
J 0
(4060 2760);
DISPLAY 0.617021 (4060 2760);
PAINT ORANGE (4060 2760);
FORCEPROP 2 LASTPIN (4050 2700) $PN 167
J 0
(4060 2710);
DISPLAY 0.617021 (4060 2710);
PAINT ORANGE (4060 2710);
FORCEPROP 2 LASTPIN (4050 2650) $PN 169
J 0
(4060 2660);
DISPLAY 0.617021 (4060 2660);
PAINT ORANGE (4060 2660);
FORCEPROP 2 LASTPIN (4050 2600) $PN 171
J 0
(4060 2610);
DISPLAY 0.617021 (4060 2610);
PAINT ORANGE (4060 2610);
FORCEPROP 2 LASTPIN (4050 2550) $PN 173
J 0
(4060 2560);
DISPLAY 0.617021 (4060 2560);
PAINT ORANGE (4060 2560);
FORCEPROP 2 LASTPIN (4050 2500) $PN 176
J 0
(4060 2510);
DISPLAY 0.617021 (4060 2510);
PAINT ORANGE (4060 2510);
FORCEPROP 2 LASTPIN (4050 2450) $PN 178
J 0
(4060 2460);
DISPLAY 0.617021 (4060 2460);
PAINT ORANGE (4060 2460);
FORCEPROP 2 LASTPIN (4050 2400) $PN 180
J 0
(4060 2410);
DISPLAY 0.617021 (4060 2410);
PAINT ORANGE (4060 2410);
FORCEPROP 2 LASTPIN (4050 2350) $PN 182
J 0
(4060 2360);
DISPLAY 0.617021 (4060 2360);
PAINT ORANGE (4060 2360);
FORCEPROP 2 LASTPIN (4050 2300) $PN 184
J 0
(4060 2310);
DISPLAY 0.617021 (4060 2310);
PAINT ORANGE (4060 2310);
FORCEPROP 2 LASTPIN (4050 2250) $PN 187
J 0
(4060 2260);
DISPLAY 0.617021 (4060 2260);
PAINT ORANGE (4060 2260);
FORCEPROP 2 LASTPIN (4050 2200) $PN 189
J 0
(4060 2210);
DISPLAY 0.617021 (4060 2210);
PAINT ORANGE (4060 2210);
FORCEPROP 2 LASTPIN (4050 2150) $PN 191
J 0
(4060 2160);
DISPLAY 0.617021 (4060 2160);
PAINT ORANGE (4060 2160);
FORCEPROP 2 LASTPIN (4050 2100) $PN 193
J 0
(4060 2110);
DISPLAY 0.617021 (4060 2110);
PAINT ORANGE (4060 2110);
FORCEPROP 2 LASTPIN (4050 2050) $PN 195
J 0
(4060 2060);
DISPLAY 0.617021 (4060 2060);
PAINT ORANGE (4060 2060);
FORCEPROP 2 LASTPIN (4050 2000) $PN 198
J 0
(4060 2010);
DISPLAY 0.617021 (4060 2010);
PAINT ORANGE (4060 2010);
FORCEPROP 2 LASTPIN (4050 1950) $PN 200
J 0
(4060 1960);
DISPLAY 0.617021 (4060 1960);
PAINT ORANGE (4060 1960);
FORCEPROP 2 LASTPIN (4050 1900) $PN 202
J 0
(4060 1910);
DISPLAY 0.617021 (4060 1910);
PAINT ORANGE (4060 1910);
FORCEPROP 2 LASTPIN (4050 1850) $PN 239
J 0
(4060 1860);
DISPLAY 0.617021 (4060 1860);
PAINT ORANGE (4060 1860);
FORCEPROP 2 LASTPIN (4050 1800) $PN 241
J 0
(4060 1810);
DISPLAY 0.617021 (4060 1810);
PAINT ORANGE (4060 1810);
FORCEPROP 2 LASTPIN (4050 1750) $PN 243
J 0
(4060 1760);
DISPLAY 0.617021 (4060 1760);
PAINT ORANGE (4060 1760);
FORCEPROP 2 LASTPIN (4050 1700) $PN 246
J 0
(4060 1710);
DISPLAY 0.617021 (4060 1710);
PAINT ORANGE (4060 1710);
FORCEPROP 2 LASTPIN (4050 1650) $PN 248
J 0
(4060 1660);
DISPLAY 0.617021 (4060 1660);
PAINT ORANGE (4060 1660);
FORCEPROP 2 LASTPIN (4050 1600) $PN 250
J 0
(4060 1610);
DISPLAY 0.617021 (4060 1610);
PAINT ORANGE (4060 1610);
FORCEPROP 2 LASTPIN (4050 1550) $PN 252
J 0
(4060 1560);
DISPLAY 0.617021 (4060 1560);
PAINT ORANGE (4060 1560);
FORCEPROP 2 LASTPIN (4050 1500) $PN 254
J 0
(4060 1510);
DISPLAY 0.617021 (4060 1510);
PAINT ORANGE (4060 1510);
FORCEPROP 2 LASTPIN (4050 1450) $PN 257
J 0
(4060 1460);
DISPLAY 0.617021 (4060 1460);
PAINT ORANGE (4060 1460);
FORCEPROP 2 LASTPIN (4050 1400) $PN 259
J 0
(4060 1410);
DISPLAY 0.617021 (4060 1410);
PAINT ORANGE (4060 1410);
FORCEPROP 2 LASTPIN (4050 1350) $PN 261
J 0
(4060 1360);
DISPLAY 0.617021 (4060 1360);
PAINT ORANGE (4060 1360);
FORCEPROP 2 LASTPIN (4050 1300) $PN 263
J 0
(4060 1310);
DISPLAY 0.617021 (4060 1310);
PAINT ORANGE (4060 1310);
FORCEPROP 2 LASTPIN (4050 1250) $PN 265
J 0
(4060 1260);
DISPLAY 0.617021 (4060 1260);
PAINT ORANGE (4060 1260);
FORCEPROP 2 LASTPIN (4050 1200) $PN 268
J 0
(4060 1210);
DISPLAY 0.617021 (4060 1210);
PAINT ORANGE (4060 1210);
FORCEPROP 2 LASTPIN (4050 1150) $PN 270
J 0
(4060 1160);
DISPLAY 0.617021 (4060 1160);
PAINT ORANGE (4060 1160);
FORCEPROP 2 LASTPIN (4050 1100) $PN 272
J 0
(4060 1110);
DISPLAY 0.617021 (4060 1110);
PAINT ORANGE (4060 1110);
FORCEPROP 2 LASTPIN (4050 1050) $PN 274
J 0
(4060 1060);
DISPLAY 0.617021 (4060 1060);
PAINT ORANGE (4060 1060);
FORCEPROP 2 LASTPIN (4050 1000) $PN 276
J 0
(4060 1010);
DISPLAY 0.617021 (4060 1010);
PAINT ORANGE (4060 1010);
FORCEPROP 2 LASTPIN (4050 950) $PN 279
J 0
(4060 960);
DISPLAY 0.617021 (4060 960);
PAINT ORANGE (4060 960);
FORCEPROP 2 LASTPIN (4050 900) $PN 281
J 0
(4060 910);
DISPLAY 0.617021 (4060 910);
PAINT ORANGE (4060 910);
FORCEPROP 2 LASTPIN (4050 850) $PN 283
J 0
(4060 860);
DISPLAY 0.617021 (4060 860);
PAINT ORANGE (4060 860);
FORCEPROP 1 LAST MATERIAL SCONN
J 0
(3100 3350);
DISPLAY 0.617021 (3100 3350);
PAINT SKYBLUE (3100 3350);
FORCEPROP 1 LAST LOCATION J9T1
J 0
(3100 3400);
DISPLAY 0.617021 (3100 3400);
PAINT AQUA (3100 3400);
FORCEPROP 2 LASTPIN (3050 1650) $PN 103
J 2
(3040 1660);
DISPLAY 0.617021 (3040 1660);
PAINT ORANGE (3040 1660);
FORCEPROP 2 LASTPIN (4050 2850) $PN 160
J 0
(4060 2860);
DISPLAY 0.617021 (4060 2860);
PAINT ORANGE (4060 2860);
FORCEPROP 2 LASTPIN (3050 2950) $PN 11
J 2
(3040 2960);
DISPLAY 0.617021 (3040 2960);
PAINT ORANGE (3040 2960);
FORCEPROP 0 LAST BOM_SS NOPOP
J 0
(3377 3366);
DISPLAY 1.021277 (3377 3366);
PAINT BROWN (3377 3366);
DISPLAY BOTH (3377 3366);
FORCEPROP 2 LASTPIN (3050 1700) $PN 101
J 2
(3040 1710);
DISPLAY 0.617021 (3040 1710);
PAINT ORANGE (3040 1710);
FORCEPROP 2 LASTPIN (3050 1200) $PN 123
J 2
(3040 1210);
DISPLAY 0.617021 (3040 1210);
PAINT ORANGE (3040 1210);
FORCEPROP 1 LAST PACK_TYPE PIP
J 0
(3100 3450);
PAINT SKYBLUE (3100 3450);
DISPLAY INVISIBLE (3100 3450);
FORCEPROP 2 LAST BOM_COST MEM
J 0
(3550 2000);
PAINT ORANGE (3550 2000);
DISPLAY INVISIBLE (3550 2000);
FORCEPROP 2 LAST CDS_LIB mstr_sconn
J 0
(3550 2000);
PAINT ORANGE (3550 2000);
DISPLAY INVISIBLE (3550 2000);
FORCEPROP 2 LAST SEC_TYPE PIP
J 0
(3100 3450);
DISPLAY 1.021277 (3100 3450);
PAINT ORANGE (3100 3450);
DISPLAY INVISIBLE (3100 3450);
FORCEPROP 2 LAST SEC 3
J 0
(3100 3450);
DISPLAY 0.680851 (3100 3450);
PAINT MONO (3100 3450);
DISPLAY INVISIBLE (3100 3450);
FORCEPROP 2 LAST CDS_LOCATION J9T1
J 0
(3100 3400);
DISPLAY 0.617021 (3100 3400);
PAINT AQUA (3100 3400);
DISPLAY INVISIBLE (3100 3400);
FORCEPROP 1 LAST PATH I144
J 0
(3550 3350);
PAINT GREEN (3550 3350);
DISPLAY INVISIBLE (3550 3350);
FORCEPROP 2 LAST ROOM DDR4_GH_G
J 0
(3550 2000);
PAINT ORANGE (3550 2000);
DISPLAY INVISIBLE (3550 2000);
FORCEADD TAP..6
R 2
(2450 3250);
FORCEPROP 3 LASTPIN (2400 3250) SIG_NAME M_G_DQS_DP<1>
J 0
(2410 3260);
DISPLAY 0.659574 (2410 3260);
PAINT MONO (2410 3260);
DISPLAY INVISIBLE (2410 3260);
FORCEPROP 1 LASTPIN (2400 3250) BN 1
J 2
(2450 3260);
DISPLAY 0.617021 (2450 3260);
PAINT PINK (2450 3260);
FORCEPROP 2 LAST CDS_LIB mstr_standard
J 0
(2450 3250);
DISPLAY 0.787234 (2450 3250);
PAINT MONO (2450 3250);
DISPLAY INVISIBLE (2450 3250);
FORCEPROP 1 LAST BODY_TYPE PLUMBING
J 2
(2450 3200);
DISPLAY 1.234043 (2450 3200);
PAINT GREEN (2450 3200);
DISPLAY INVISIBLE (2450 3200);
FORCEPROP 1 LAST HDL_TAP TRUE
J 2
(2125 3125);
DISPLAY 1.234043 (2125 3125);
PAINT GREEN (2125 3125);
DISPLAY INVISIBLE (2125 3125);
FORCEPROP 1 LAST PATH I148
J 2
(2452 3250);
DISPLAY 0.872340 (2452 3250);
PAINT GREEN (2452 3250);
DISPLAY INVISIBLE (2452 3250);
FORCEADD TAP..6
R 2
(2450 3150);
FORCEPROP 3 LASTPIN (2400 3150) SIG_NAME M_G_DQS_DP<0>
J 0
(2410 3160);
DISPLAY 0.659574 (2410 3160);
PAINT MONO (2410 3160);
DISPLAY INVISIBLE (2410 3160);
FORCEPROP 1 LASTPIN (2400 3150) BN 0
J 2
(2450 3160);
DISPLAY 0.617021 (2450 3160);
PAINT PINK (2450 3160);
FORCEPROP 2 LAST CDS_LIB mstr_standard
J 0
(2450 3150);
DISPLAY 0.787234 (2450 3150);
PAINT MONO (2450 3150);
DISPLAY INVISIBLE (2450 3150);
FORCEPROP 1 LAST BODY_TYPE PLUMBING
J 2
(2450 3100);
DISPLAY 1.234043 (2450 3100);
PAINT GREEN (2450 3100);
DISPLAY INVISIBLE (2450 3100);
FORCEPROP 1 LAST HDL_TAP TRUE
J 2
(2125 3025);
DISPLAY 1.234043 (2125 3025);
PAINT GREEN (2125 3025);
DISPLAY INVISIBLE (2125 3025);
FORCEPROP 1 LAST PATH I149
J 2
(2452 3150);
DISPLAY 0.872340 (2452 3150);
PAINT GREEN (2452 3150);
DISPLAY INVISIBLE (2452 3150);
FORCEADD OFFPAGE..6
(-2025 2225);
FORCEPROP 2 LAST $XR1 77 
J 0
(-2364 2225);
DISPLAY 0.638298 (-2364 2225);
PAINT MONO (-2364 2225);
FORCEPROP 2 LAST $XR0 57 
J 0
(-2274 2225);
DISPLAY 0.638298 (-2274 2225);
PAINT MONO (-2274 2225);
FORCEPROP 2 LAST CDS_LIB mstr_standard
J 0
(-2025 2225);
DISPLAY 0.787234 (-2025 2225);
PAINT MONO (-2025 2225);
DISPLAY INVISIBLE (-2025 2225);
FORCEPROP 1 LAST OFFPAGE TRUE
J 0
(-1700 2100);
DISPLAY 0.936170 (-1700 2100);
PAINT GREEN (-1700 2100);
DISPLAY INVISIBLE (-1700 2100);
FORCEPROP 1 LAST COMMENT_BODY TRUE
J 0
(-1925 2150);
DISPLAY 0.936170 (-1925 2150);
PAINT GREEN (-1925 2150);
DISPLAY INVISIBLE (-1925 2150);
FORCEPROP 2 LAST PATH I15
J 0
(-2250 2275);
DISPLAY 1.021277 (-2250 2275);
PAINT ORANGE (-2250 2275);
DISPLAY INVISIBLE (-2250 2275);
FORCEADD TAP..6
R 2
(2450 3350);
FORCEPROP 3 LASTPIN (2400 3350) SIG_NAME M_G_DQS_DP<2>
J 0
(2410 3360);
DISPLAY 0.659574 (2410 3360);
PAINT MONO (2410 3360);
DISPLAY INVISIBLE (2410 3360);
FORCEPROP 1 LASTPIN (2400 3350) BN 2
J 2
(2450 3360);
DISPLAY 0.617021 (2450 3360);
PAINT PINK (2450 3360);
FORCEPROP 2 LAST CDS_LIB mstr_standard
J 0
(2450 3350);
DISPLAY 0.787234 (2450 3350);
PAINT MONO (2450 3350);
DISPLAY INVISIBLE (2450 3350);
FORCEPROP 1 LAST BODY_TYPE PLUMBING
J 2
(2450 3300);
DISPLAY 1.234043 (2450 3300);
PAINT GREEN (2450 3300);
DISPLAY INVISIBLE (2450 3300);
FORCEPROP 1 LAST HDL_TAP TRUE
J 2
(2125 3225);
DISPLAY 1.234043 (2125 3225);
PAINT GREEN (2125 3225);
DISPLAY INVISIBLE (2125 3225);
FORCEPROP 1 LAST PATH I150
J 2
(2452 3350);
DISPLAY 0.872340 (2452 3350);
PAINT GREEN (2452 3350);
DISPLAY INVISIBLE (2452 3350);
FORCEADD TAP..6
R 2
(2650 3100);
FORCEPROP 3 LASTPIN (2600 3100) SIG_NAME M_G_DQS_DN<0>
J 0
(2610 3110);
DISPLAY 0.659574 (2610 3110);
PAINT MONO (2610 3110);
DISPLAY INVISIBLE (2610 3110);
FORCEPROP 1 LASTPIN (2600 3100) BN 0
J 2
(2650 3110);
DISPLAY 0.617021 (2650 3110);
PAINT PINK (2650 3110);
FORCEPROP 2 LAST CDS_LIB mstr_standard
J 0
(2650 3100);
DISPLAY 0.787234 (2650 3100);
PAINT MONO (2650 3100);
DISPLAY INVISIBLE (2650 3100);
FORCEPROP 1 LAST BODY_TYPE PLUMBING
J 2
(2650 3050);
DISPLAY 1.234043 (2650 3050);
PAINT GREEN (2650 3050);
DISPLAY INVISIBLE (2650 3050);
FORCEPROP 1 LAST HDL_TAP TRUE
J 2
(2325 2975);
DISPLAY 1.234043 (2325 2975);
PAINT GREEN (2325 2975);
DISPLAY INVISIBLE (2325 2975);
FORCEPROP 1 LAST PATH I151
J 2
(2652 3100);
DISPLAY 0.872340 (2652 3100);
PAINT GREEN (2652 3100);
DISPLAY INVISIBLE (2652 3100);
FORCEADD TAP..6
R 2
(2650 3200);
FORCEPROP 3 LASTPIN (2600 3200) SIG_NAME M_G_DQS_DN<1>
J 0
(2610 3210);
DISPLAY 0.659574 (2610 3210);
PAINT MONO (2610 3210);
DISPLAY INVISIBLE (2610 3210);
FORCEPROP 1 LASTPIN (2600 3200) BN 1
J 2
(2650 3210);
DISPLAY 0.617021 (2650 3210);
PAINT PINK (2650 3210);
FORCEPROP 2 LAST CDS_LIB mstr_standard
J 0
(2650 3200);
DISPLAY 0.787234 (2650 3200);
PAINT MONO (2650 3200);
DISPLAY INVISIBLE (2650 3200);
FORCEPROP 1 LAST BODY_TYPE PLUMBING
J 2
(2650 3150);
DISPLAY 1.234043 (2650 3150);
PAINT GREEN (2650 3150);
DISPLAY INVISIBLE (2650 3150);
FORCEPROP 1 LAST HDL_TAP TRUE
J 2
(2325 3075);
DISPLAY 1.234043 (2325 3075);
PAINT GREEN (2325 3075);
DISPLAY INVISIBLE (2325 3075);
FORCEPROP 1 LAST PATH I152
J 2
(2652 3200);
DISPLAY 0.872340 (2652 3200);
PAINT GREEN (2652 3200);
DISPLAY INVISIBLE (2652 3200);
FORCEADD TAP..6
R 2
(2650 3300);
FORCEPROP 3 LASTPIN (2600 3300) SIG_NAME M_G_DQS_DN<2>
J 0
(2610 3310);
DISPLAY 0.659574 (2610 3310);
PAINT MONO (2610 3310);
DISPLAY INVISIBLE (2610 3310);
FORCEPROP 1 LASTPIN (2600 3300) BN 2
J 2
(2650 3310);
DISPLAY 0.617021 (2650 3310);
PAINT PINK (2650 3310);
FORCEPROP 2 LAST CDS_LIB mstr_standard
J 0
(2650 3300);
DISPLAY 0.787234 (2650 3300);
PAINT MONO (2650 3300);
DISPLAY INVISIBLE (2650 3300);
FORCEPROP 1 LAST BODY_TYPE PLUMBING
J 2
(2650 3250);
DISPLAY 1.234043 (2650 3250);
PAINT GREEN (2650 3250);
DISPLAY INVISIBLE (2650 3250);
FORCEPROP 1 LAST HDL_TAP TRUE
J 2
(2325 3175);
DISPLAY 1.234043 (2325 3175);
PAINT GREEN (2325 3175);
DISPLAY INVISIBLE (2325 3175);
FORCEPROP 1 LAST PATH I153
J 2
(2652 3300);
DISPLAY 0.872340 (2652 3300);
PAINT GREEN (2652 3300);
DISPLAY INVISIBLE (2652 3300);
FORCEADD TAP..6
R 2
(2450 3450);
FORCEPROP 3 LASTPIN (2400 3450) SIG_NAME M_G_DQS_DP<3>
J 0
(2410 3460);
DISPLAY 0.659574 (2410 3460);
PAINT MONO (2410 3460);
DISPLAY INVISIBLE (2410 3460);
FORCEPROP 1 LASTPIN (2400 3450) BN 3
J 2
(2450 3460);
DISPLAY 0.617021 (2450 3460);
PAINT PINK (2450 3460);
FORCEPROP 2 LAST CDS_LIB mstr_standard
J 0
(2450 3450);
DISPLAY 0.787234 (2450 3450);
PAINT MONO (2450 3450);
DISPLAY INVISIBLE (2450 3450);
FORCEPROP 1 LAST BODY_TYPE PLUMBING
J 2
(2450 3400);
DISPLAY 1.234043 (2450 3400);
PAINT GREEN (2450 3400);
DISPLAY INVISIBLE (2450 3400);
FORCEPROP 1 LAST HDL_TAP TRUE
J 2
(2125 3325);
DISPLAY 1.234043 (2125 3325);
PAINT GREEN (2125 3325);
DISPLAY INVISIBLE (2125 3325);
FORCEPROP 1 LAST PATH I154
J 2
(2452 3450);
DISPLAY 0.872340 (2452 3450);
PAINT GREEN (2452 3450);
DISPLAY INVISIBLE (2452 3450);
FORCEADD TAP..6
R 2
(2450 3550);
FORCEPROP 3 LASTPIN (2400 3550) SIG_NAME M_G_DQS_DP<4>
J 0
(2410 3560);
DISPLAY 0.659574 (2410 3560);
PAINT MONO (2410 3560);
DISPLAY INVISIBLE (2410 3560);
FORCEPROP 1 LASTPIN (2400 3550) BN 4
J 2
(2450 3560);
DISPLAY 0.617021 (2450 3560);
PAINT PINK (2450 3560);
FORCEPROP 2 LAST CDS_LIB mstr_standard
J 0
(2450 3550);
DISPLAY 0.787234 (2450 3550);
PAINT MONO (2450 3550);
DISPLAY INVISIBLE (2450 3550);
FORCEPROP 1 LAST BODY_TYPE PLUMBING
J 2
(2450 3500);
DISPLAY 1.234043 (2450 3500);
PAINT GREEN (2450 3500);
DISPLAY INVISIBLE (2450 3500);
FORCEPROP 1 LAST HDL_TAP TRUE
J 2
(2125 3425);
DISPLAY 1.234043 (2125 3425);
PAINT GREEN (2125 3425);
DISPLAY INVISIBLE (2125 3425);
FORCEPROP 1 LAST PATH I155
J 2
(2452 3550);
DISPLAY 0.872340 (2452 3550);
PAINT GREEN (2452 3550);
DISPLAY INVISIBLE (2452 3550);
FORCEADD TAP..6
R 2
(2450 3750);
FORCEPROP 3 LASTPIN (2400 3750) SIG_NAME M_G_DQS_DP<6>
J 0
(2410 3760);
DISPLAY 0.659574 (2410 3760);
PAINT MONO (2410 3760);
DISPLAY INVISIBLE (2410 3760);
FORCEPROP 1 LASTPIN (2400 3750) BN 6
J 2
(2450 3760);
DISPLAY 0.617021 (2450 3760);
PAINT PINK (2450 3760);
FORCEPROP 2 LAST CDS_LIB mstr_standard
J 0
(2450 3750);
DISPLAY 0.787234 (2450 3750);
PAINT MONO (2450 3750);
DISPLAY INVISIBLE (2450 3750);
FORCEPROP 1 LAST BODY_TYPE PLUMBING
J 2
(2450 3700);
DISPLAY 1.234043 (2450 3700);
PAINT GREEN (2450 3700);
DISPLAY INVISIBLE (2450 3700);
FORCEPROP 1 LAST HDL_TAP TRUE
J 2
(2125 3625);
DISPLAY 1.234043 (2125 3625);
PAINT GREEN (2125 3625);
DISPLAY INVISIBLE (2125 3625);
FORCEPROP 1 LAST PATH I156
J 2
(2452 3750);
DISPLAY 0.872340 (2452 3750);
PAINT GREEN (2452 3750);
DISPLAY INVISIBLE (2452 3750);
FORCEADD TAP..6
R 2
(2450 3650);
FORCEPROP 3 LASTPIN (2400 3650) SIG_NAME M_G_DQS_DP<5>
J 0
(2410 3660);
DISPLAY 0.659574 (2410 3660);
PAINT MONO (2410 3660);
DISPLAY INVISIBLE (2410 3660);
FORCEPROP 1 LASTPIN (2400 3650) BN 5
J 2
(2450 3660);
DISPLAY 0.617021 (2450 3660);
PAINT PINK (2450 3660);
FORCEPROP 2 LAST CDS_LIB mstr_standard
J 0
(2450 3650);
DISPLAY 0.787234 (2450 3650);
PAINT MONO (2450 3650);
DISPLAY INVISIBLE (2450 3650);
FORCEPROP 1 LAST BODY_TYPE PLUMBING
J 2
(2450 3600);
DISPLAY 1.234043 (2450 3600);
PAINT GREEN (2450 3600);
DISPLAY INVISIBLE (2450 3600);
FORCEPROP 1 LAST HDL_TAP TRUE
J 2
(2125 3525);
DISPLAY 1.234043 (2125 3525);
PAINT GREEN (2125 3525);
DISPLAY INVISIBLE (2125 3525);
FORCEPROP 1 LAST PATH I157
J 2
(2452 3650);
DISPLAY 0.872340 (2452 3650);
PAINT GREEN (2452 3650);
DISPLAY INVISIBLE (2452 3650);
FORCEADD TAP..6
R 2
(2450 3850);
FORCEPROP 3 LASTPIN (2400 3850) SIG_NAME M_G_DQS_DP<7>
J 0
(2410 3860);
DISPLAY 0.659574 (2410 3860);
PAINT MONO (2410 3860);
DISPLAY INVISIBLE (2410 3860);
FORCEPROP 1 LASTPIN (2400 3850) BN 7
J 2
(2450 3860);
DISPLAY 0.617021 (2450 3860);
PAINT PINK (2450 3860);
FORCEPROP 2 LAST CDS_LIB mstr_standard
J 0
(2450 3850);
DISPLAY 0.787234 (2450 3850);
PAINT MONO (2450 3850);
DISPLAY INVISIBLE (2450 3850);
FORCEPROP 1 LAST BODY_TYPE PLUMBING
J 2
(2450 3800);
DISPLAY 1.234043 (2450 3800);
PAINT GREEN (2450 3800);
DISPLAY INVISIBLE (2450 3800);
FORCEPROP 1 LAST HDL_TAP TRUE
J 2
(2125 3725);
DISPLAY 1.234043 (2125 3725);
PAINT GREEN (2125 3725);
DISPLAY INVISIBLE (2125 3725);
FORCEPROP 1 LAST PATH I158
J 2
(2452 3850);
DISPLAY 0.872340 (2452 3850);
PAINT GREEN (2452 3850);
DISPLAY INVISIBLE (2452 3850);
FORCEADD TAP..6
R 2
(2650 3500);
FORCEPROP 3 LASTPIN (2600 3500) SIG_NAME M_G_DQS_DN<4>
J 0
(2610 3510);
DISPLAY 0.659574 (2610 3510);
PAINT MONO (2610 3510);
DISPLAY INVISIBLE (2610 3510);
FORCEPROP 1 LASTPIN (2600 3500) BN 4
J 2
(2650 3510);
DISPLAY 0.617021 (2650 3510);
PAINT PINK (2650 3510);
FORCEPROP 2 LAST CDS_LIB mstr_standard
J 0
(2650 3500);
DISPLAY 0.787234 (2650 3500);
PAINT MONO (2650 3500);
DISPLAY INVISIBLE (2650 3500);
FORCEPROP 1 LAST BODY_TYPE PLUMBING
J 2
(2650 3450);
DISPLAY 1.234043 (2650 3450);
PAINT GREEN (2650 3450);
DISPLAY INVISIBLE (2650 3450);
FORCEPROP 1 LAST HDL_TAP TRUE
J 2
(2325 3375);
DISPLAY 1.234043 (2325 3375);
PAINT GREEN (2325 3375);
DISPLAY INVISIBLE (2325 3375);
FORCEPROP 1 LAST PATH I159
J 2
(2652 3500);
DISPLAY 0.872340 (2652 3500);
PAINT GREEN (2652 3500);
DISPLAY INVISIBLE (2652 3500);
FORCEADD OFFPAGE..1
(-2025 2175);
FORCEPROP 2 LAST $XR1 77 
J 0
(-2366 2175);
DISPLAY 0.638298 (-2366 2175);
PAINT MONO (-2366 2175);
FORCEPROP 2 LAST $XR0 57 
J 0
(-2276 2175);
DISPLAY 0.638298 (-2276 2175);
PAINT MONO (-2276 2175);
FORCEPROP 2 LAST CDS_LIB mstr_standard
J 0
(-2025 2175);
DISPLAY 0.787234 (-2025 2175);
PAINT MONO (-2025 2175);
DISPLAY INVISIBLE (-2025 2175);
FORCEPROP 1 LAST OFFPAGE TRUE
J 0
(-1700 2050);
DISPLAY 0.936170 (-1700 2050);
PAINT GREEN (-1700 2050);
DISPLAY INVISIBLE (-1700 2050);
FORCEPROP 1 LAST COMMENT_BODY TRUE
J 0
(-1900 2075);
DISPLAY 0.936170 (-1900 2075);
PAINT GREEN (-1900 2075);
DISPLAY INVISIBLE (-1900 2075);
FORCEPROP 2 LAST PATH I16
J 0
(-2275 2225);
DISPLAY 1.021277 (-2275 2225);
PAINT ORANGE (-2275 2225);
DISPLAY INVISIBLE (-2275 2225);
FORCEADD TAP..6
R 2
(2650 3400);
FORCEPROP 3 LASTPIN (2600 3400) SIG_NAME M_G_DQS_DN<3>
J 0
(2610 3410);
DISPLAY 0.659574 (2610 3410);
PAINT MONO (2610 3410);
DISPLAY INVISIBLE (2610 3410);
FORCEPROP 1 LASTPIN (2600 3400) BN 3
J 2
(2650 3410);
DISPLAY 0.617021 (2650 3410);
PAINT PINK (2650 3410);
FORCEPROP 2 LAST CDS_LIB mstr_standard
J 0
(2650 3400);
DISPLAY 0.787234 (2650 3400);
PAINT MONO (2650 3400);
DISPLAY INVISIBLE (2650 3400);
FORCEPROP 1 LAST BODY_TYPE PLUMBING
J 2
(2650 3350);
DISPLAY 1.234043 (2650 3350);
PAINT GREEN (2650 3350);
DISPLAY INVISIBLE (2650 3350);
FORCEPROP 1 LAST HDL_TAP TRUE
J 2
(2325 3275);
DISPLAY 1.234043 (2325 3275);
PAINT GREEN (2325 3275);
DISPLAY INVISIBLE (2325 3275);
FORCEPROP 1 LAST PATH I160
J 2
(2652 3400);
DISPLAY 0.872340 (2652 3400);
PAINT GREEN (2652 3400);
DISPLAY INVISIBLE (2652 3400);
FORCEADD TAP..6
R 2
(2650 3600);
FORCEPROP 3 LASTPIN (2600 3600) SIG_NAME M_G_DQS_DN<5>
J 0
(2610 3610);
DISPLAY 0.659574 (2610 3610);
PAINT MONO (2610 3610);
DISPLAY INVISIBLE (2610 3610);
FORCEPROP 1 LASTPIN (2600 3600) BN 5
J 2
(2650 3610);
DISPLAY 0.617021 (2650 3610);
PAINT PINK (2650 3610);
FORCEPROP 2 LAST CDS_LIB mstr_standard
J 0
(2650 3600);
DISPLAY 0.787234 (2650 3600);
PAINT MONO (2650 3600);
DISPLAY INVISIBLE (2650 3600);
FORCEPROP 1 LAST BODY_TYPE PLUMBING
J 2
(2650 3550);
DISPLAY 1.234043 (2650 3550);
PAINT GREEN (2650 3550);
DISPLAY INVISIBLE (2650 3550);
FORCEPROP 1 LAST HDL_TAP TRUE
J 2
(2325 3475);
DISPLAY 1.234043 (2325 3475);
PAINT GREEN (2325 3475);
DISPLAY INVISIBLE (2325 3475);
FORCEPROP 1 LAST PATH I161
J 2
(2652 3600);
DISPLAY 0.872340 (2652 3600);
PAINT GREEN (2652 3600);
DISPLAY INVISIBLE (2652 3600);
FORCEADD TAP..6
R 2
(2650 3800);
FORCEPROP 3 LASTPIN (2600 3800) SIG_NAME M_G_DQS_DN<7>
J 0
(2610 3810);
DISPLAY 0.659574 (2610 3810);
PAINT MONO (2610 3810);
DISPLAY INVISIBLE (2610 3810);
FORCEPROP 1 LASTPIN (2600 3800) BN 7
J 2
(2650 3810);
DISPLAY 0.617021 (2650 3810);
PAINT PINK (2650 3810);
FORCEPROP 2 LAST CDS_LIB mstr_standard
J 0
(2650 3800);
DISPLAY 0.787234 (2650 3800);
PAINT MONO (2650 3800);
DISPLAY INVISIBLE (2650 3800);
FORCEPROP 1 LAST BODY_TYPE PLUMBING
J 2
(2650 3750);
DISPLAY 1.234043 (2650 3750);
PAINT GREEN (2650 3750);
DISPLAY INVISIBLE (2650 3750);
FORCEPROP 1 LAST HDL_TAP TRUE
J 2
(2325 3675);
DISPLAY 1.234043 (2325 3675);
PAINT GREEN (2325 3675);
DISPLAY INVISIBLE (2325 3675);
FORCEPROP 1 LAST PATH I162
J 2
(2652 3800);
DISPLAY 0.872340 (2652 3800);
PAINT GREEN (2652 3800);
DISPLAY INVISIBLE (2652 3800);
FORCEADD TAP..6
R 2
(2650 3700);
FORCEPROP 3 LASTPIN (2600 3700) SIG_NAME M_G_DQS_DN<6>
J 0
(2610 3710);
DISPLAY 0.659574 (2610 3710);
PAINT MONO (2610 3710);
DISPLAY INVISIBLE (2610 3710);
FORCEPROP 1 LASTPIN (2600 3700) BN 6
J 2
(2650 3710);
DISPLAY 0.617021 (2650 3710);
PAINT PINK (2650 3710);
FORCEPROP 2 LAST CDS_LIB mstr_standard
J 0
(2650 3700);
DISPLAY 0.787234 (2650 3700);
PAINT MONO (2650 3700);
DISPLAY INVISIBLE (2650 3700);
FORCEPROP 1 LAST BODY_TYPE PLUMBING
J 2
(2650 3650);
DISPLAY 1.234043 (2650 3650);
PAINT GREEN (2650 3650);
DISPLAY INVISIBLE (2650 3650);
FORCEPROP 1 LAST HDL_TAP TRUE
J 2
(2325 3575);
DISPLAY 1.234043 (2325 3575);
PAINT GREEN (2325 3575);
DISPLAY INVISIBLE (2325 3575);
FORCEPROP 1 LAST PATH I163
J 2
(2652 3700);
DISPLAY 0.872340 (2652 3700);
PAINT GREEN (2652 3700);
DISPLAY INVISIBLE (2652 3700);
FORCEADD GND..1
R 2
(4250 700);
FORCEPROP 3 LASTPIN (4250 750) SIG_NAME GND\g
J 0
(4260 760);
DISPLAY 0.659574 (4260 760);
PAINT MONO (4260 760);
DISPLAY INVISIBLE (4260 760);
FORCEPROP 1 LAST VOLTAGE 0.0V
J 2
(4295 657);
DISPLAY 0.340426 (4295 657);
PAINT SKYBLUE (4295 657);
DISPLAY INVISIBLE (4295 657);
FORCEPROP 1 LAST SIZE 1B
J 2
(4175 650);
DISPLAY 1.170213 (4175 650);
PAINT GREEN (4175 650);
DISPLAY INVISIBLE (4175 650);
FORCEPROP 2 LAST CDS_LIB mstr_symbols
J 0
(4250 700);
DISPLAY 0.787234 (4250 700);
PAINT MONO (4250 700);
DISPLAY INVISIBLE (4250 700);
FORCEPROP 2 LAST BOM_COST MEM
J 0
(4250 705);
PAINT ORANGE (4250 705);
DISPLAY INVISIBLE (4250 705);
FORCEPROP 1 LAST BODY_TYPE PLUMBING
J 2
(4295 657);
DISPLAY 0.340426 (4295 657);
PAINT GREEN (4295 657);
DISPLAY INVISIBLE (4295 657);
FORCEPROP 1 LAST PATH I164
J 2
(4175 700);
DISPLAY 0.872340 (4175 700);
PAINT AQUA (4175 700);
DISPLAY INVISIBLE (4175 700);
FORCEPROP 2 LAST ROOM DDR4_GH_G
J 0
(4250 705);
PAINT ORANGE (4250 705);
DISPLAY INVISIBLE (4250 705);
FORCEPROP 1 LAST HDL_POWER GND
J 2
(4250 850);
DISPLAY 0.553191 (4250 850);
PAINT GREEN (4250 850);
DISPLAY INVISIBLE (4250 850);
FORCEADD TAP..6
R 2
(2450 3950);
FORCEPROP 3 LASTPIN (2400 3950) SIG_NAME M_G_DQS_DP<8>
J 0
(2410 3960);
DISPLAY 0.659574 (2410 3960);
PAINT MONO (2410 3960);
DISPLAY INVISIBLE (2410 3960);
FORCEPROP 1 LASTPIN (2400 3950) BN 8
J 2
(2450 3960);
DISPLAY 0.617021 (2450 3960);
PAINT PINK (2450 3960);
FORCEPROP 2 LAST CDS_LIB mstr_standard
J 0
(2450 3950);
DISPLAY 0.787234 (2450 3950);
PAINT MONO (2450 3950);
DISPLAY INVISIBLE (2450 3950);
FORCEPROP 1 LAST BODY_TYPE PLUMBING
J 2
(2450 3900);
DISPLAY 1.234043 (2450 3900);
PAINT GREEN (2450 3900);
DISPLAY INVISIBLE (2450 3900);
FORCEPROP 1 LAST HDL_TAP TRUE
J 2
(2125 3825);
DISPLAY 1.234043 (2125 3825);
PAINT GREEN (2125 3825);
DISPLAY INVISIBLE (2125 3825);
FORCEPROP 1 LAST PATH I165
J 2
(2452 3950);
DISPLAY 0.872340 (2452 3950);
PAINT GREEN (2452 3950);
DISPLAY INVISIBLE (2452 3950);
FORCEADD TAP..6
R 2
(2450 4150);
FORCEPROP 3 LASTPIN (2400 4150) SIG_NAME M_G_DQS_DP<10>
J 0
(2410 4160);
DISPLAY 0.659574 (2410 4160);
PAINT MONO (2410 4160);
DISPLAY INVISIBLE (2410 4160);
FORCEPROP 1 LASTPIN (2400 4150) BN 10
J 2
(2450 4160);
DISPLAY 0.617021 (2450 4160);
PAINT PINK (2450 4160);
FORCEPROP 2 LAST CDS_LIB mstr_standard
J 0
(2450 4150);
DISPLAY 0.787234 (2450 4150);
PAINT MONO (2450 4150);
DISPLAY INVISIBLE (2450 4150);
FORCEPROP 1 LAST BODY_TYPE PLUMBING
J 2
(2450 4100);
DISPLAY 1.234043 (2450 4100);
PAINT GREEN (2450 4100);
DISPLAY INVISIBLE (2450 4100);
FORCEPROP 1 LAST HDL_TAP TRUE
J 2
(2125 4025);
DISPLAY 1.234043 (2125 4025);
PAINT GREEN (2125 4025);
DISPLAY INVISIBLE (2125 4025);
FORCEPROP 1 LAST PATH I166
J 2
(2452 4150);
DISPLAY 0.872340 (2452 4150);
PAINT GREEN (2452 4150);
DISPLAY INVISIBLE (2452 4150);
FORCEADD TAP..6
R 2
(2450 4050);
FORCEPROP 3 LASTPIN (2400 4050) SIG_NAME M_G_DQS_DP<9>
J 0
(2410 4060);
DISPLAY 0.659574 (2410 4060);
PAINT MONO (2410 4060);
DISPLAY INVISIBLE (2410 4060);
FORCEPROP 1 LASTPIN (2400 4050) BN 9
J 2
(2450 4060);
DISPLAY 0.617021 (2450 4060);
PAINT PINK (2450 4060);
FORCEPROP 2 LAST CDS_LIB mstr_standard
J 0
(2450 4050);
DISPLAY 0.787234 (2450 4050);
PAINT MONO (2450 4050);
DISPLAY INVISIBLE (2450 4050);
FORCEPROP 1 LAST BODY_TYPE PLUMBING
J 2
(2450 4000);
DISPLAY 1.234043 (2450 4000);
PAINT GREEN (2450 4000);
DISPLAY INVISIBLE (2450 4000);
FORCEPROP 1 LAST HDL_TAP TRUE
J 2
(2125 3925);
DISPLAY 1.234043 (2125 3925);
PAINT GREEN (2125 3925);
DISPLAY INVISIBLE (2125 3925);
FORCEPROP 1 LAST PATH I167
J 2
(2452 4050);
DISPLAY 0.872340 (2452 4050);
PAINT GREEN (2452 4050);
DISPLAY INVISIBLE (2452 4050);
FORCEADD TAP..6
R 2
(2450 4250);
FORCEPROP 3 LASTPIN (2400 4250) SIG_NAME M_G_DQS_DP<11>
J 0
(2410 4260);
DISPLAY 0.659574 (2410 4260);
PAINT MONO (2410 4260);
DISPLAY INVISIBLE (2410 4260);
FORCEPROP 1 LASTPIN (2400 4250) BN 11
J 2
(2450 4260);
DISPLAY 0.617021 (2450 4260);
PAINT PINK (2450 4260);
FORCEPROP 2 LAST CDS_LIB mstr_standard
J 0
(2450 4250);
DISPLAY 0.787234 (2450 4250);
PAINT MONO (2450 4250);
DISPLAY INVISIBLE (2450 4250);
FORCEPROP 1 LAST BODY_TYPE PLUMBING
J 2
(2450 4200);
DISPLAY 1.234043 (2450 4200);
PAINT GREEN (2450 4200);
DISPLAY INVISIBLE (2450 4200);
FORCEPROP 1 LAST HDL_TAP TRUE
J 2
(2125 4125);
DISPLAY 1.234043 (2125 4125);
PAINT GREEN (2125 4125);
DISPLAY INVISIBLE (2125 4125);
FORCEPROP 1 LAST PATH I168
J 2
(2452 4250);
DISPLAY 0.872340 (2452 4250);
PAINT GREEN (2452 4250);
DISPLAY INVISIBLE (2452 4250);
FORCEADD TAP..6
R 2
(2450 4350);
FORCEPROP 3 LASTPIN (2400 4350) SIG_NAME M_G_DQS_DP<12>
J 0
(2410 4360);
DISPLAY 0.659574 (2410 4360);
PAINT MONO (2410 4360);
DISPLAY INVISIBLE (2410 4360);
FORCEPROP 1 LASTPIN (2400 4350) BN 12
J 2
(2450 4360);
DISPLAY 0.617021 (2450 4360);
PAINT PINK (2450 4360);
FORCEPROP 2 LAST CDS_LIB mstr_standard
J 0
(2450 4350);
DISPLAY 0.787234 (2450 4350);
PAINT MONO (2450 4350);
DISPLAY INVISIBLE (2450 4350);
FORCEPROP 1 LAST BODY_TYPE PLUMBING
J 2
(2450 4300);
DISPLAY 1.234043 (2450 4300);
PAINT GREEN (2450 4300);
DISPLAY INVISIBLE (2450 4300);
FORCEPROP 1 LAST HDL_TAP TRUE
J 2
(2125 4225);
DISPLAY 1.234043 (2125 4225);
PAINT GREEN (2125 4225);
DISPLAY INVISIBLE (2125 4225);
FORCEPROP 1 LAST PATH I169
J 2
(2452 4350);
DISPLAY 0.872340 (2452 4350);
PAINT GREEN (2452 4350);
DISPLAY INVISIBLE (2452 4350);
FORCEADD OFFPAGE..1
(-2025 2375);
FORCEPROP 2 LAST $XR1 77 
J 0
(-2336 2375);
DISPLAY 0.638298 (-2336 2375);
PAINT MONO (-2336 2375);
FORCEPROP 2 LAST $XR0 57 
J 0
(-2246 2375);
DISPLAY 0.638298 (-2246 2375);
PAINT MONO (-2246 2375);
FORCEPROP 2 LAST CDS_LIB mstr_standard
J 0
(-2025 2375);
DISPLAY 0.787234 (-2025 2375);
PAINT MONO (-2025 2375);
DISPLAY INVISIBLE (-2025 2375);
FORCEPROP 1 LAST OFFPAGE TRUE
J 0
(-1700 2250);
DISPLAY 0.936170 (-1700 2250);
PAINT GREEN (-1700 2250);
DISPLAY INVISIBLE (-1700 2250);
FORCEPROP 1 LAST COMMENT_BODY TRUE
J 0
(-1900 2275);
DISPLAY 0.936170 (-1900 2275);
PAINT GREEN (-1900 2275);
DISPLAY INVISIBLE (-1900 2275);
FORCEPROP 2 LAST PATH I17
J 0
(-2225 2425);
DISPLAY 1.021277 (-2225 2425);
PAINT ORANGE (-2225 2425);
DISPLAY INVISIBLE (-2225 2425);
FORCEADD TAP..6
R 2
(2650 4000);
FORCEPROP 3 LASTPIN (2600 4000) SIG_NAME M_G_DQS_DN<9>
J 0
(2610 4010);
DISPLAY 0.659574 (2610 4010);
PAINT MONO (2610 4010);
DISPLAY INVISIBLE (2610 4010);
FORCEPROP 1 LASTPIN (2600 4000) BN 9
J 2
(2650 4010);
DISPLAY 0.617021 (2650 4010);
PAINT PINK (2650 4010);
FORCEPROP 2 LAST CDS_LIB mstr_standard
J 0
(2650 4000);
DISPLAY 0.787234 (2650 4000);
PAINT MONO (2650 4000);
DISPLAY INVISIBLE (2650 4000);
FORCEPROP 1 LAST BODY_TYPE PLUMBING
J 2
(2650 3950);
DISPLAY 1.234043 (2650 3950);
PAINT GREEN (2650 3950);
DISPLAY INVISIBLE (2650 3950);
FORCEPROP 1 LAST HDL_TAP TRUE
J 2
(2325 3875);
DISPLAY 1.234043 (2325 3875);
PAINT GREEN (2325 3875);
DISPLAY INVISIBLE (2325 3875);
FORCEPROP 1 LAST PATH I170
J 2
(2652 4000);
DISPLAY 0.872340 (2652 4000);
PAINT GREEN (2652 4000);
DISPLAY INVISIBLE (2652 4000);
FORCEADD TAP..6
R 2
(2650 4100);
FORCEPROP 3 LASTPIN (2600 4100) SIG_NAME M_G_DQS_DN<10>
J 0
(2610 4110);
DISPLAY 0.659574 (2610 4110);
PAINT MONO (2610 4110);
DISPLAY INVISIBLE (2610 4110);
FORCEPROP 1 LASTPIN (2600 4100) BN 10
J 2
(2650 4110);
DISPLAY 0.617021 (2650 4110);
PAINT PINK (2650 4110);
FORCEPROP 2 LAST CDS_LIB mstr_standard
J 0
(2650 4100);
DISPLAY 0.787234 (2650 4100);
PAINT MONO (2650 4100);
DISPLAY INVISIBLE (2650 4100);
FORCEPROP 1 LAST BODY_TYPE PLUMBING
J 2
(2650 4050);
DISPLAY 1.234043 (2650 4050);
PAINT GREEN (2650 4050);
DISPLAY INVISIBLE (2650 4050);
FORCEPROP 1 LAST HDL_TAP TRUE
J 2
(2325 3975);
DISPLAY 1.234043 (2325 3975);
PAINT GREEN (2325 3975);
DISPLAY INVISIBLE (2325 3975);
FORCEPROP 1 LAST PATH I171
J 2
(2652 4100);
DISPLAY 0.872340 (2652 4100);
PAINT GREEN (2652 4100);
DISPLAY INVISIBLE (2652 4100);
FORCEADD TAP..6
R 2
(2650 3900);
FORCEPROP 3 LASTPIN (2600 3900) SIG_NAME M_G_DQS_DN<8>
J 0
(2610 3910);
DISPLAY 0.659574 (2610 3910);
PAINT MONO (2610 3910);
DISPLAY INVISIBLE (2610 3910);
FORCEPROP 1 LASTPIN (2600 3900) BN 8
J 2
(2650 3910);
DISPLAY 0.617021 (2650 3910);
PAINT PINK (2650 3910);
FORCEPROP 2 LAST CDS_LIB mstr_standard
J 0
(2650 3900);
DISPLAY 0.787234 (2650 3900);
PAINT MONO (2650 3900);
DISPLAY INVISIBLE (2650 3900);
FORCEPROP 1 LAST BODY_TYPE PLUMBING
J 2
(2650 3850);
DISPLAY 1.234043 (2650 3850);
PAINT GREEN (2650 3850);
DISPLAY INVISIBLE (2650 3850);
FORCEPROP 1 LAST HDL_TAP TRUE
J 2
(2325 3775);
DISPLAY 1.234043 (2325 3775);
PAINT GREEN (2325 3775);
DISPLAY INVISIBLE (2325 3775);
FORCEPROP 1 LAST PATH I172
J 2
(2652 3900);
DISPLAY 0.872340 (2652 3900);
PAINT GREEN (2652 3900);
DISPLAY INVISIBLE (2652 3900);
FORCEADD TAP..6
R 2
(2650 4200);
FORCEPROP 3 LASTPIN (2600 4200) SIG_NAME M_G_DQS_DN<11>
J 0
(2610 4210);
DISPLAY 0.659574 (2610 4210);
PAINT MONO (2610 4210);
DISPLAY INVISIBLE (2610 4210);
FORCEPROP 1 LASTPIN (2600 4200) BN 11
J 2
(2650 4210);
DISPLAY 0.617021 (2650 4210);
PAINT PINK (2650 4210);
FORCEPROP 2 LAST CDS_LIB mstr_standard
J 0
(2650 4200);
DISPLAY 0.787234 (2650 4200);
PAINT MONO (2650 4200);
DISPLAY INVISIBLE (2650 4200);
FORCEPROP 1 LAST BODY_TYPE PLUMBING
J 2
(2650 4150);
DISPLAY 1.234043 (2650 4150);
PAINT GREEN (2650 4150);
DISPLAY INVISIBLE (2650 4150);
FORCEPROP 1 LAST HDL_TAP TRUE
J 2
(2325 4075);
DISPLAY 1.234043 (2325 4075);
PAINT GREEN (2325 4075);
DISPLAY INVISIBLE (2325 4075);
FORCEPROP 1 LAST PATH I173
J 2
(2652 4200);
DISPLAY 0.872340 (2652 4200);
PAINT GREEN (2652 4200);
DISPLAY INVISIBLE (2652 4200);
FORCEADD TAP..6
R 2
(2650 4400);
FORCEPROP 3 LASTPIN (2600 4400) SIG_NAME M_G_DQS_DN<13>
J 0
(2610 4410);
DISPLAY 0.659574 (2610 4410);
PAINT MONO (2610 4410);
DISPLAY INVISIBLE (2610 4410);
FORCEPROP 1 LASTPIN (2600 4400) BN 13
J 2
(2650 4410);
DISPLAY 0.617021 (2650 4410);
PAINT PINK (2650 4410);
FORCEPROP 2 LAST CDS_LIB mstr_standard
J 0
(2650 4400);
DISPLAY 0.787234 (2650 4400);
PAINT MONO (2650 4400);
DISPLAY INVISIBLE (2650 4400);
FORCEPROP 1 LAST BODY_TYPE PLUMBING
J 2
(2650 4350);
DISPLAY 1.234043 (2650 4350);
PAINT GREEN (2650 4350);
DISPLAY INVISIBLE (2650 4350);
FORCEPROP 1 LAST HDL_TAP TRUE
J 2
(2325 4275);
DISPLAY 1.234043 (2325 4275);
PAINT GREEN (2325 4275);
DISPLAY INVISIBLE (2325 4275);
FORCEPROP 1 LAST PATH I174
J 2
(2652 4400);
DISPLAY 0.872340 (2652 4400);
PAINT GREEN (2652 4400);
DISPLAY INVISIBLE (2652 4400);
FORCEADD TAP..6
R 2
(2650 4300);
FORCEPROP 3 LASTPIN (2600 4300) SIG_NAME M_G_DQS_DN<12>
J 0
(2610 4310);
DISPLAY 0.659574 (2610 4310);
PAINT MONO (2610 4310);
DISPLAY INVISIBLE (2610 4310);
FORCEPROP 1 LASTPIN (2600 4300) BN 12
J 2
(2650 4310);
DISPLAY 0.617021 (2650 4310);
PAINT PINK (2650 4310);
FORCEPROP 2 LAST CDS_LIB mstr_standard
J 0
(2650 4300);
DISPLAY 0.787234 (2650 4300);
PAINT MONO (2650 4300);
DISPLAY INVISIBLE (2650 4300);
FORCEPROP 1 LAST BODY_TYPE PLUMBING
J 2
(2650 4250);
DISPLAY 1.234043 (2650 4250);
PAINT GREEN (2650 4250);
DISPLAY INVISIBLE (2650 4250);
FORCEPROP 1 LAST HDL_TAP TRUE
J 2
(2325 4175);
DISPLAY 1.234043 (2325 4175);
PAINT GREEN (2325 4175);
DISPLAY INVISIBLE (2325 4175);
FORCEPROP 1 LAST PATH I175
J 2
(2652 4300);
DISPLAY 0.872340 (2652 4300);
PAINT GREEN (2652 4300);
DISPLAY INVISIBLE (2652 4300);
FORCEADD TAP..6
R 2
(2450 4450);
FORCEPROP 3 LASTPIN (2400 4450) SIG_NAME M_G_DQS_DP<13>
J 0
(2410 4460);
DISPLAY 0.659574 (2410 4460);
PAINT MONO (2410 4460);
DISPLAY INVISIBLE (2410 4460);
FORCEPROP 1 LASTPIN (2400 4450) BN 13
J 2
(2450 4460);
DISPLAY 0.617021 (2450 4460);
PAINT PINK (2450 4460);
FORCEPROP 2 LAST CDS_LIB mstr_standard
J 0
(2450 4450);
DISPLAY 0.787234 (2450 4450);
PAINT MONO (2450 4450);
DISPLAY INVISIBLE (2450 4450);
FORCEPROP 1 LAST BODY_TYPE PLUMBING
J 2
(2450 4400);
DISPLAY 1.234043 (2450 4400);
PAINT GREEN (2450 4400);
DISPLAY INVISIBLE (2450 4400);
FORCEPROP 1 LAST HDL_TAP TRUE
J 2
(2125 4325);
DISPLAY 1.234043 (2125 4325);
PAINT GREEN (2125 4325);
DISPLAY INVISIBLE (2125 4325);
FORCEPROP 1 LAST PATH I176
J 2
(2452 4450);
DISPLAY 0.872340 (2452 4450);
PAINT GREEN (2452 4450);
DISPLAY INVISIBLE (2452 4450);
FORCEADD TAP..6
R 2
(2450 4550);
FORCEPROP 3 LASTPIN (2400 4550) SIG_NAME M_G_DQS_DP<14>
J 0
(2410 4560);
DISPLAY 0.659574 (2410 4560);
PAINT MONO (2410 4560);
DISPLAY INVISIBLE (2410 4560);
FORCEPROP 1 LASTPIN (2400 4550) BN 14
J 2
(2450 4560);
DISPLAY 0.617021 (2450 4560);
PAINT PINK (2450 4560);
FORCEPROP 2 LAST CDS_LIB mstr_standard
J 0
(2450 4550);
DISPLAY 0.787234 (2450 4550);
PAINT MONO (2450 4550);
DISPLAY INVISIBLE (2450 4550);
FORCEPROP 1 LAST BODY_TYPE PLUMBING
J 2
(2450 4500);
DISPLAY 1.234043 (2450 4500);
PAINT GREEN (2450 4500);
DISPLAY INVISIBLE (2450 4500);
FORCEPROP 1 LAST HDL_TAP TRUE
J 2
(2125 4425);
DISPLAY 1.234043 (2125 4425);
PAINT GREEN (2125 4425);
DISPLAY INVISIBLE (2125 4425);
FORCEPROP 1 LAST PATH I177
J 2
(2452 4550);
DISPLAY 0.872340 (2452 4550);
PAINT GREEN (2452 4550);
DISPLAY INVISIBLE (2452 4550);
FORCEADD TAP..6
R 2
(2450 4650);
FORCEPROP 3 LASTPIN (2400 4650) SIG_NAME M_G_DQS_DP<15>
J 0
(2410 4660);
DISPLAY 0.659574 (2410 4660);
PAINT MONO (2410 4660);
DISPLAY INVISIBLE (2410 4660);
FORCEPROP 1 LASTPIN (2400 4650) BN 15
J 2
(2450 4660);
DISPLAY 0.617021 (2450 4660);
PAINT PINK (2450 4660);
FORCEPROP 2 LAST CDS_LIB mstr_standard
J 0
(2450 4650);
DISPLAY 0.787234 (2450 4650);
PAINT MONO (2450 4650);
DISPLAY INVISIBLE (2450 4650);
FORCEPROP 1 LAST BODY_TYPE PLUMBING
J 2
(2450 4600);
DISPLAY 1.234043 (2450 4600);
PAINT GREEN (2450 4600);
DISPLAY INVISIBLE (2450 4600);
FORCEPROP 1 LAST HDL_TAP TRUE
J 2
(2125 4525);
DISPLAY 1.234043 (2125 4525);
PAINT GREEN (2125 4525);
DISPLAY INVISIBLE (2125 4525);
FORCEPROP 1 LAST PATH I178
J 2
(2452 4650);
DISPLAY 0.872340 (2452 4650);
PAINT GREEN (2452 4650);
DISPLAY INVISIBLE (2452 4650);
FORCEADD TAP..6
R 2
(2450 4750);
FORCEPROP 3 LASTPIN (2400 4750) SIG_NAME M_G_DQS_DP<16>
J 0
(2410 4760);
DISPLAY 0.659574 (2410 4760);
PAINT MONO (2410 4760);
DISPLAY INVISIBLE (2410 4760);
FORCEPROP 1 LASTPIN (2400 4750) BN 16
J 2
(2450 4760);
DISPLAY 0.617021 (2450 4760);
PAINT PINK (2450 4760);
FORCEPROP 2 LAST CDS_LIB mstr_standard
J 0
(2450 4750);
DISPLAY 0.787234 (2450 4750);
PAINT MONO (2450 4750);
DISPLAY INVISIBLE (2450 4750);
FORCEPROP 1 LAST BODY_TYPE PLUMBING
J 2
(2450 4700);
DISPLAY 1.234043 (2450 4700);
PAINT GREEN (2450 4700);
DISPLAY INVISIBLE (2450 4700);
FORCEPROP 1 LAST HDL_TAP TRUE
J 2
(2125 4625);
DISPLAY 1.234043 (2125 4625);
PAINT GREEN (2125 4625);
DISPLAY INVISIBLE (2125 4625);
FORCEPROP 1 LAST PATH I179
J 2
(2452 4750);
DISPLAY 0.872340 (2452 4750);
PAINT GREEN (2452 4750);
DISPLAY INVISIBLE (2452 4750);
FORCEADD OFFPAGE..1
(-2025 2525);
FORCEPROP 2 LAST $XR1 77 
J 0
(-2336 2525);
DISPLAY 0.638298 (-2336 2525);
PAINT MONO (-2336 2525);
FORCEPROP 2 LAST $XR0 57 
J 0
(-2246 2525);
DISPLAY 0.638298 (-2246 2525);
PAINT MONO (-2246 2525);
FORCEPROP 2 LAST CDS_LIB mstr_standard
J 0
(-2025 2525);
DISPLAY 0.787234 (-2025 2525);
PAINT MONO (-2025 2525);
DISPLAY INVISIBLE (-2025 2525);
FORCEPROP 1 LAST OFFPAGE TRUE
J 0
(-1700 2400);
DISPLAY 0.936170 (-1700 2400);
PAINT GREEN (-1700 2400);
DISPLAY INVISIBLE (-1700 2400);
FORCEPROP 1 LAST COMMENT_BODY TRUE
J 0
(-1900 2425);
DISPLAY 0.936170 (-1900 2425);
PAINT GREEN (-1900 2425);
DISPLAY INVISIBLE (-1900 2425);
FORCEPROP 2 LAST PATH I18
J 0
(-2225 2575);
DISPLAY 1.021277 (-2225 2575);
PAINT ORANGE (-2225 2575);
DISPLAY INVISIBLE (-2225 2575);
FORCEADD TAP..6
R 2
(2450 4850);
FORCEPROP 3 LASTPIN (2400 4850) SIG_NAME M_G_DQS_DP<17>
J 0
(2410 4860);
DISPLAY 0.659574 (2410 4860);
PAINT MONO (2410 4860);
DISPLAY INVISIBLE (2410 4860);
FORCEPROP 1 LASTPIN (2400 4850) BN 17
J 2
(2450 4860);
DISPLAY 0.617021 (2450 4860);
PAINT PINK (2450 4860);
FORCEPROP 2 LAST CDS_LIB mstr_standard
J 2
(2450 4850);
DISPLAY 0.787234 (2450 4850);
PAINT MONO (2450 4850);
DISPLAY INVISIBLE (2450 4850);
FORCEPROP 1 LAST BODY_TYPE PLUMBING
J 2
(2450 4800);
DISPLAY 1.234043 (2450 4800);
PAINT GREEN (2450 4800);
DISPLAY INVISIBLE (2450 4800);
FORCEPROP 1 LAST HDL_TAP TRUE
J 2
(2125 4725);
DISPLAY 1.234043 (2125 4725);
PAINT GREEN (2125 4725);
DISPLAY INVISIBLE (2125 4725);
FORCEPROP 1 LAST PATH I180
J 2
(2452 4850);
DISPLAY 0.872340 (2452 4850);
PAINT GREEN (2452 4850);
DISPLAY INVISIBLE (2452 4850);
FORCEADD TAP..6
R 2
(2650 4600);
FORCEPROP 3 LASTPIN (2600 4600) SIG_NAME M_G_DQS_DN<15>
J 0
(2610 4610);
DISPLAY 0.659574 (2610 4610);
PAINT MONO (2610 4610);
DISPLAY INVISIBLE (2610 4610);
FORCEPROP 1 LASTPIN (2600 4600) BN 15
J 2
(2650 4610);
DISPLAY 0.617021 (2650 4610);
PAINT PINK (2650 4610);
FORCEPROP 2 LAST CDS_LIB mstr_standard
J 0
(2650 4600);
DISPLAY 0.787234 (2650 4600);
PAINT MONO (2650 4600);
DISPLAY INVISIBLE (2650 4600);
FORCEPROP 1 LAST BODY_TYPE PLUMBING
J 2
(2650 4550);
DISPLAY 1.234043 (2650 4550);
PAINT GREEN (2650 4550);
DISPLAY INVISIBLE (2650 4550);
FORCEPROP 1 LAST HDL_TAP TRUE
J 2
(2325 4475);
DISPLAY 1.234043 (2325 4475);
PAINT GREEN (2325 4475);
DISPLAY INVISIBLE (2325 4475);
FORCEPROP 1 LAST PATH I181
J 2
(2652 4600);
DISPLAY 0.872340 (2652 4600);
PAINT GREEN (2652 4600);
DISPLAY INVISIBLE (2652 4600);
FORCEADD TAP..6
R 2
(2650 4500);
FORCEPROP 3 LASTPIN (2600 4500) SIG_NAME M_G_DQS_DN<14>
J 0
(2610 4510);
DISPLAY 0.659574 (2610 4510);
PAINT MONO (2610 4510);
DISPLAY INVISIBLE (2610 4510);
FORCEPROP 1 LASTPIN (2600 4500) BN 14
J 2
(2650 4510);
DISPLAY 0.617021 (2650 4510);
PAINT PINK (2650 4510);
FORCEPROP 2 LAST CDS_LIB mstr_standard
J 0
(2650 4500);
DISPLAY 0.787234 (2650 4500);
PAINT MONO (2650 4500);
DISPLAY INVISIBLE (2650 4500);
FORCEPROP 1 LAST BODY_TYPE PLUMBING
J 2
(2650 4450);
DISPLAY 1.234043 (2650 4450);
PAINT GREEN (2650 4450);
DISPLAY INVISIBLE (2650 4450);
FORCEPROP 1 LAST HDL_TAP TRUE
J 2
(2325 4375);
DISPLAY 1.234043 (2325 4375);
PAINT GREEN (2325 4375);
DISPLAY INVISIBLE (2325 4375);
FORCEPROP 1 LAST PATH I182
J 2
(2652 4500);
DISPLAY 0.872340 (2652 4500);
PAINT GREEN (2652 4500);
DISPLAY INVISIBLE (2652 4500);
FORCEADD TAP..6
R 2
(2650 4800);
FORCEPROP 3 LASTPIN (2600 4800) SIG_NAME M_G_DQS_DN<17>
J 0
(2610 4810);
DISPLAY 0.659574 (2610 4810);
PAINT MONO (2610 4810);
DISPLAY INVISIBLE (2610 4810);
FORCEPROP 1 LASTPIN (2600 4800) BN 17
J 2
(2650 4810);
DISPLAY 0.617021 (2650 4810);
PAINT PINK (2650 4810);
FORCEPROP 2 LAST CDS_LIB mstr_standard
J 2
(2650 4800);
DISPLAY 0.787234 (2650 4800);
PAINT MONO (2650 4800);
DISPLAY INVISIBLE (2650 4800);
FORCEPROP 1 LAST BODY_TYPE PLUMBING
J 2
(2650 4750);
DISPLAY 1.234043 (2650 4750);
PAINT GREEN (2650 4750);
DISPLAY INVISIBLE (2650 4750);
FORCEPROP 1 LAST HDL_TAP TRUE
J 2
(2325 4675);
DISPLAY 1.234043 (2325 4675);
PAINT GREEN (2325 4675);
DISPLAY INVISIBLE (2325 4675);
FORCEPROP 1 LAST PATH I183
J 2
(2652 4800);
DISPLAY 0.872340 (2652 4800);
PAINT GREEN (2652 4800);
DISPLAY INVISIBLE (2652 4800);
FORCEADD TAP..6
R 2
(2650 4700);
FORCEPROP 3 LASTPIN (2600 4700) SIG_NAME M_G_DQS_DN<16>
J 0
(2610 4710);
DISPLAY 0.659574 (2610 4710);
PAINT MONO (2610 4710);
DISPLAY INVISIBLE (2610 4710);
FORCEPROP 1 LASTPIN (2600 4700) BN 16
J 2
(2650 4710);
DISPLAY 0.617021 (2650 4710);
PAINT PINK (2650 4710);
FORCEPROP 2 LAST CDS_LIB mstr_standard
J 0
(2650 4700);
DISPLAY 0.787234 (2650 4700);
PAINT MONO (2650 4700);
DISPLAY INVISIBLE (2650 4700);
FORCEPROP 1 LAST BODY_TYPE PLUMBING
J 2
(2650 4650);
DISPLAY 1.234043 (2650 4650);
PAINT GREEN (2650 4650);
DISPLAY INVISIBLE (2650 4650);
FORCEPROP 1 LAST HDL_TAP TRUE
J 2
(2325 4575);
DISPLAY 1.234043 (2325 4575);
PAINT GREEN (2325 4575);
DISPLAY INVISIBLE (2325 4575);
FORCEPROP 1 LAST PATH I184
J 2
(2652 4700);
DISPLAY 0.872340 (2652 4700);
PAINT GREEN (2652 4700);
DISPLAY INVISIBLE (2652 4700);
FORCEADD OFFPAGE..3
(3350 4850);
FORCEPROP 2 LAST $XR1 77 
J 0
(3654 4850);
DISPLAY 0.638298 (3654 4850);
PAINT MONO (3654 4850);
FORCEPROP 2 LAST $XR0 57 
J 0
(3564 4850);
DISPLAY 0.638298 (3564 4850);
PAINT MONO (3564 4850);
FORCEPROP 2 LAST CDS_LIB mstr_standard
J 0
(3350 4850);
DISPLAY 0.787234 (3350 4850);
PAINT MONO (3350 4850);
DISPLAY INVISIBLE (3350 4850);
FORCEPROP 1 LAST OFFPAGE TRUE
J 0
(3675 4725);
DISPLAY 0.936170 (3675 4725);
PAINT GREEN (3675 4725);
DISPLAY INVISIBLE (3675 4725);
FORCEPROP 1 LAST COMMENT_BODY TRUE
J 0
(3300 4750);
DISPLAY 0.936170 (3300 4750);
PAINT GREEN (3300 4750);
DISPLAY INVISIBLE (3300 4750);
FORCEPROP 2 LAST PATH I185
J 0
(3575 4900);
DISPLAY 1.021277 (3575 4900);
PAINT ORANGE (3575 4900);
DISPLAY INVISIBLE (3575 4900);
FORCEADD OFFPAGE..3
(3350 4900);
FORCEPROP 2 LAST $XR1 77 
J 0
(3654 4900);
DISPLAY 0.638298 (3654 4900);
PAINT MONO (3654 4900);
FORCEPROP 2 LAST $XR0 57 
J 0
(3564 4900);
DISPLAY 0.638298 (3564 4900);
PAINT MONO (3564 4900);
FORCEPROP 2 LAST CDS_LIB mstr_standard
J 0
(3350 4900);
DISPLAY 0.787234 (3350 4900);
PAINT MONO (3350 4900);
DISPLAY INVISIBLE (3350 4900);
FORCEPROP 1 LAST OFFPAGE TRUE
J 0
(3675 4775);
DISPLAY 0.936170 (3675 4775);
PAINT GREEN (3675 4775);
DISPLAY INVISIBLE (3675 4775);
FORCEPROP 1 LAST COMMENT_BODY TRUE
J 0
(3300 4800);
DISPLAY 0.936170 (3300 4800);
PAINT GREEN (3300 4800);
DISPLAY INVISIBLE (3300 4800);
FORCEPROP 2 LAST PATH I186
J 0
(3575 4950);
DISPLAY 1.021277 (3575 4950);
PAINT ORANGE (3575 4950);
DISPLAY INVISIBLE (3575 4950);
FORCEADD P12V_NVDIMM_GHJ..1
(2150 2725);
FORCEPROP 3 LASTPIN (2150 2675) SIG_NAME P12V_NVDIMM_GHJ\g
J 0
(2160 2685);
DISPLAY 0.659574 (2160 2685);
PAINT MONO (2160 2685);
DISPLAY INVISIBLE (2160 2685);
FORCEPROP 1 LAST VOLTAGE 12.0
J 0
(2105 2682);
DISPLAY 0.340426 (2105 2682);
PAINT SKYBLUE (2105 2682);
DISPLAY INVISIBLE (2105 2682);
FORCEPROP 2 LAST CDS_LIB mstr_symbols
J 0
(2150 2725);
PAINT ORANGE (2150 2725);
DISPLAY INVISIBLE (2150 2725);
FORCEPROP 1 LAST BODY_TYPE PLUMBING
J 0
(2105 2682);
DISPLAY 0.340426 (2105 2682);
PAINT GREEN (2105 2682);
DISPLAY INVISIBLE (2105 2682);
FORCEPROP 1 LAST PATH I187
J 0
(2200 2750);
DISPLAY 0.872340 (2200 2750);
PAINT AQUA (2200 2750);
DISPLAY INVISIBLE (2200 2750);
FORCEPROP 1 LAST HDL_POWER P12V_NVDIMM_GHJ
J 1
(2150 2775);
DISPLAY 0.872340 (2150 2775);
PAINT GREEN (2150 2775);
DISPLAY INVISIBLE (2150 2775);
FORCEADD OFFPAGE..1
(-2025 2775);
FORCEPROP 2 LAST $XR1 77 
J 0
(-2336 2775);
DISPLAY 0.638298 (-2336 2775);
PAINT MONO (-2336 2775);
FORCEPROP 2 LAST $XR0 57 
J 0
(-2246 2775);
DISPLAY 0.638298 (-2246 2775);
PAINT MONO (-2246 2775);
FORCEPROP 2 LAST CDS_LIB mstr_standard
J 0
(-2025 2775);
DISPLAY 0.787234 (-2025 2775);
PAINT MONO (-2025 2775);
DISPLAY INVISIBLE (-2025 2775);
FORCEPROP 1 LAST OFFPAGE TRUE
J 0
(-1700 2650);
DISPLAY 0.936170 (-1700 2650);
PAINT GREEN (-1700 2650);
DISPLAY INVISIBLE (-1700 2650);
FORCEPROP 1 LAST COMMENT_BODY TRUE
J 0
(-1900 2675);
DISPLAY 0.936170 (-1900 2675);
PAINT GREEN (-1900 2675);
DISPLAY INVISIBLE (-1900 2675);
FORCEPROP 2 LAST PATH I19
J 0
(-2225 2825);
DISPLAY 1.021277 (-2225 2825);
PAINT ORANGE (-2225 2825);
DISPLAY INVISIBLE (-2225 2825);
FORCEADD CAP_A..1
R 2
(-2675 875);
FORCEPROP 1 LAST LOCATION C9T7
J 2
(-2725 975);
DISPLAY 0.617021 (-2725 975);
PAINT AQUA (-2725 975);
FORCEPROP 1 LAST PART_NUMBER A36096-045
J 2
(-2725 725);
DISPLAY 0.617021 (-2725 725);
PAINT BLUE (-2725 725);
FORCEPROP 1 LAST VALUE 0.01UF
J 2
(-2725 925);
DISPLAY 0.617021 (-2725 925);
PAINT SKYBLUE (-2725 925);
FORCEPROP 1 LAST TOLERANCE 10%
J 2
(-2725 825);
DISPLAY 0.617021 (-2725 825);
PAINT SKYBLUE (-2725 825);
FORCEPROP 1 LAST PACK_TYPE 0402V
J 2
(-2725 675);
DISPLAY 0.617021 (-2725 675);
PAINT SKYBLUE (-2725 675);
FORCEPROP 1 LAST VOLTAGE 25V
J 2
(-2725 875);
DISPLAY 0.617021 (-2725 875);
PAINT SKYBLUE (-2725 875);
FORCEPROP 1 LAST MATERIAL X7R
J 2
(-2725 775);
DISPLAY 0.617021 (-2725 775);
PAINT SKYBLUE (-2725 775);
FORCEPROP 2 LAST CDS_LOCATION C9T7
J 2
(-2725 975);
DISPLAY 0.617021 (-2725 975);
PAINT AQUA (-2725 975);
DISPLAY INVISIBLE (-2725 975);
FORCEPROP 2 LAST BOM_COST MEM
J 0
(-2675 875);
PAINT ORANGE (-2675 875);
DISPLAY INVISIBLE (-2675 875);
FORCEPROP 2 LAST CDS_LIB dev_discrete
J 0
(-2675 875);
PAINT ORANGE (-2675 875);
DISPLAY INVISIBLE (-2675 875);
FORCEPROP 2 LAST CDS_SEC 1
J 0
(-2725 1075);
PAINT MONO (-2725 1075);
DISPLAY INVISIBLE (-2725 1075);
FORCEPROP 2 LAST $SEC 1
J 0
(-2725 1075);
PAINT MONO (-2725 1075);
DISPLAY INVISIBLE (-2725 1075);
FORCEPROP 1 LAST PATH I2
J 2
(-2725 1025);
DISPLAY 0.978723 (-2725 1025);
PAINT WHITE (-2725 1025);
DISPLAY INVISIBLE (-2725 1025);
FORCEPROP 2 LAST ROOM DDR4_GH_G
J 0
(-2675 875);
PAINT ORANGE (-2675 875);
DISPLAY INVISIBLE (-2675 875);
FORCEPROP 1 LASTPIN (-2675 975) $PN 1
J 2
(-2685 955);
DISPLAY 0.787234 (-2685 955);
PAINT ORANGE (-2685 955);
DISPLAY INVISIBLE (-2685 955);
FORCEPROP 1 LASTPIN (-2675 775) $PN 2
J 2
(-2685 755);
DISPLAY 0.787234 (-2685 755);
PAINT ORANGE (-2685 755);
DISPLAY INVISIBLE (-2685 755);
FORCEADD OFFPAGE..1
(-2025 2825);
FORCEPROP 2 LAST $XR1 77 
J 0
(-2336 2825);
DISPLAY 0.638298 (-2336 2825);
PAINT MONO (-2336 2825);
FORCEPROP 2 LAST $XR0 57 
J 0
(-2246 2825);
DISPLAY 0.638298 (-2246 2825);
PAINT MONO (-2246 2825);
FORCEPROP 2 LAST CDS_LIB mstr_standard
J 0
(-2025 2825);
DISPLAY 0.787234 (-2025 2825);
PAINT MONO (-2025 2825);
DISPLAY INVISIBLE (-2025 2825);
FORCEPROP 1 LAST OFFPAGE TRUE
J 0
(-1700 2700);
DISPLAY 0.936170 (-1700 2700);
PAINT GREEN (-1700 2700);
DISPLAY INVISIBLE (-1700 2700);
FORCEPROP 1 LAST COMMENT_BODY TRUE
J 0
(-1900 2725);
DISPLAY 0.936170 (-1900 2725);
PAINT GREEN (-1900 2725);
DISPLAY INVISIBLE (-1900 2725);
FORCEPROP 2 LAST PATH I20
J 0
(-2225 2875);
DISPLAY 1.021277 (-2225 2875);
PAINT ORANGE (-2225 2875);
DISPLAY INVISIBLE (-2225 2875);
FORCEADD TAP..6
(-1375 1875);
FORCEPROP 3 LASTPIN (-1325 1875) SIG_NAME M_G_ECC<1>
J 0
(-1315 1885);
DISPLAY 0.659574 (-1315 1885);
PAINT MONO (-1315 1885);
DISPLAY INVISIBLE (-1315 1885);
FORCEPROP 1 LASTPIN (-1325 1875) BN 1
J 0
(-1375 1885);
DISPLAY 0.617021 (-1375 1885);
PAINT PINK (-1375 1885);
FORCEPROP 2 LAST CDS_LIB mstr_standard
J 0
(-1375 1875);
DISPLAY 0.787234 (-1375 1875);
PAINT MONO (-1375 1875);
DISPLAY INVISIBLE (-1375 1875);
FORCEPROP 1 LAST BODY_TYPE PLUMBING
J 0
(-1375 1825);
DISPLAY 1.234043 (-1375 1825);
PAINT GREEN (-1375 1825);
DISPLAY INVISIBLE (-1375 1825);
FORCEPROP 1 LAST HDL_TAP TRUE
J 0
(-1050 1750);
DISPLAY 1.234043 (-1050 1750);
PAINT GREEN (-1050 1750);
DISPLAY INVISIBLE (-1050 1750);
FORCEPROP 1 LAST PATH I21
J 0
(-1377 1875);
DISPLAY 0.872340 (-1377 1875);
PAINT GREEN (-1377 1875);
DISPLAY INVISIBLE (-1377 1875);
FORCEADD TAP..6
(-1375 1925);
FORCEPROP 3 LASTPIN (-1325 1925) SIG_NAME M_G_ECC<2>
J 0
(-1315 1935);
DISPLAY 0.659574 (-1315 1935);
PAINT MONO (-1315 1935);
DISPLAY INVISIBLE (-1315 1935);
FORCEPROP 1 LASTPIN (-1325 1925) BN 2
J 0
(-1375 1935);
DISPLAY 0.617021 (-1375 1935);
PAINT PINK (-1375 1935);
FORCEPROP 2 LAST CDS_LIB mstr_standard
J 0
(-1375 1925);
DISPLAY 0.787234 (-1375 1925);
PAINT MONO (-1375 1925);
DISPLAY INVISIBLE (-1375 1925);
FORCEPROP 1 LAST BODY_TYPE PLUMBING
J 0
(-1375 1875);
DISPLAY 1.234043 (-1375 1875);
PAINT GREEN (-1375 1875);
DISPLAY INVISIBLE (-1375 1875);
FORCEPROP 1 LAST HDL_TAP TRUE
J 0
(-1050 1800);
DISPLAY 1.234043 (-1050 1800);
PAINT GREEN (-1050 1800);
DISPLAY INVISIBLE (-1050 1800);
FORCEPROP 1 LAST PATH I22
J 0
(-1377 1925);
DISPLAY 0.872340 (-1377 1925);
PAINT GREEN (-1377 1925);
DISPLAY INVISIBLE (-1377 1925);
FORCEADD TAP..6
(-1375 1975);
FORCEPROP 3 LASTPIN (-1325 1975) SIG_NAME M_G_ECC<3>
J 0
(-1315 1985);
DISPLAY 0.659574 (-1315 1985);
PAINT MONO (-1315 1985);
DISPLAY INVISIBLE (-1315 1985);
FORCEPROP 1 LASTPIN (-1325 1975) BN 3
J 0
(-1375 1985);
DISPLAY 0.617021 (-1375 1985);
PAINT PINK (-1375 1985);
FORCEPROP 2 LAST CDS_LIB mstr_standard
J 0
(-1375 1975);
DISPLAY 0.787234 (-1375 1975);
PAINT MONO (-1375 1975);
DISPLAY INVISIBLE (-1375 1975);
FORCEPROP 1 LAST BODY_TYPE PLUMBING
J 0
(-1375 1925);
DISPLAY 1.234043 (-1375 1925);
PAINT GREEN (-1375 1925);
DISPLAY INVISIBLE (-1375 1925);
FORCEPROP 1 LAST HDL_TAP TRUE
J 0
(-1050 1850);
DISPLAY 1.234043 (-1050 1850);
PAINT GREEN (-1050 1850);
DISPLAY INVISIBLE (-1050 1850);
FORCEPROP 1 LAST PATH I23
J 0
(-1377 1975);
DISPLAY 0.872340 (-1377 1975);
PAINT GREEN (-1377 1975);
DISPLAY INVISIBLE (-1377 1975);
FORCEADD TAP..6
(-1375 2075);
FORCEPROP 3 LASTPIN (-1325 2075) SIG_NAME M_G_ECC<5>
J 0
(-1315 2085);
DISPLAY 0.659574 (-1315 2085);
PAINT MONO (-1315 2085);
DISPLAY INVISIBLE (-1315 2085);
FORCEPROP 1 LASTPIN (-1325 2075) BN 5
J 0
(-1375 2085);
DISPLAY 0.617021 (-1375 2085);
PAINT PINK (-1375 2085);
FORCEPROP 2 LAST CDS_LIB mstr_standard
J 0
(-1375 2075);
DISPLAY 0.787234 (-1375 2075);
PAINT MONO (-1375 2075);
DISPLAY INVISIBLE (-1375 2075);
FORCEPROP 1 LAST BODY_TYPE PLUMBING
J 0
(-1375 2025);
DISPLAY 1.234043 (-1375 2025);
PAINT GREEN (-1375 2025);
DISPLAY INVISIBLE (-1375 2025);
FORCEPROP 1 LAST HDL_TAP TRUE
J 0
(-1050 1950);
DISPLAY 1.234043 (-1050 1950);
PAINT GREEN (-1050 1950);
DISPLAY INVISIBLE (-1050 1950);
FORCEPROP 1 LAST PATH I24
J 0
(-1377 2075);
DISPLAY 0.872340 (-1377 2075);
PAINT GREEN (-1377 2075);
DISPLAY INVISIBLE (-1377 2075);
FORCEADD TAP..6
(-1375 2025);
FORCEPROP 3 LASTPIN (-1325 2025) SIG_NAME M_G_ECC<4>
J 0
(-1315 2035);
DISPLAY 0.659574 (-1315 2035);
PAINT MONO (-1315 2035);
DISPLAY INVISIBLE (-1315 2035);
FORCEPROP 1 LASTPIN (-1325 2025) BN 4
J 0
(-1375 2035);
DISPLAY 0.617021 (-1375 2035);
PAINT PINK (-1375 2035);
FORCEPROP 2 LAST CDS_LIB mstr_standard
J 0
(-1375 2025);
DISPLAY 0.787234 (-1375 2025);
PAINT MONO (-1375 2025);
DISPLAY INVISIBLE (-1375 2025);
FORCEPROP 1 LAST BODY_TYPE PLUMBING
J 0
(-1375 1975);
DISPLAY 1.234043 (-1375 1975);
PAINT GREEN (-1375 1975);
DISPLAY INVISIBLE (-1375 1975);
FORCEPROP 1 LAST HDL_TAP TRUE
J 0
(-1050 1900);
DISPLAY 1.234043 (-1050 1900);
PAINT GREEN (-1050 1900);
DISPLAY INVISIBLE (-1050 1900);
FORCEPROP 1 LAST PATH I25
J 0
(-1377 2025);
DISPLAY 0.872340 (-1377 2025);
PAINT GREEN (-1377 2025);
DISPLAY INVISIBLE (-1377 2025);
FORCEADD TAP..6
(-1375 2175);
FORCEPROP 3 LASTPIN (-1325 2175) SIG_NAME M_G_ECC<7>
J 0
(-1315 2185);
DISPLAY 0.659574 (-1315 2185);
PAINT MONO (-1315 2185);
DISPLAY INVISIBLE (-1315 2185);
FORCEPROP 1 LASTPIN (-1325 2175) BN 7
J 0
(-1375 2185);
DISPLAY 0.617021 (-1375 2185);
PAINT PINK (-1375 2185);
FORCEPROP 2 LAST CDS_LIB mstr_standard
J 0
(-1375 2175);
DISPLAY 0.787234 (-1375 2175);
PAINT MONO (-1375 2175);
DISPLAY INVISIBLE (-1375 2175);
FORCEPROP 1 LAST BODY_TYPE PLUMBING
J 0
(-1375 2125);
DISPLAY 1.234043 (-1375 2125);
PAINT GREEN (-1375 2125);
DISPLAY INVISIBLE (-1375 2125);
FORCEPROP 1 LAST HDL_TAP TRUE
J 0
(-1050 2050);
DISPLAY 1.234043 (-1050 2050);
PAINT GREEN (-1050 2050);
DISPLAY INVISIBLE (-1050 2050);
FORCEPROP 1 LAST PATH I26
J 0
(-1377 2175);
DISPLAY 0.872340 (-1377 2175);
PAINT GREEN (-1377 2175);
DISPLAY INVISIBLE (-1377 2175);
FORCEADD TAP..6
(-1375 2125);
FORCEPROP 3 LASTPIN (-1325 2125) SIG_NAME M_G_ECC<6>
J 0
(-1315 2135);
DISPLAY 0.659574 (-1315 2135);
PAINT MONO (-1315 2135);
DISPLAY INVISIBLE (-1315 2135);
FORCEPROP 1 LASTPIN (-1325 2125) BN 6
J 0
(-1375 2135);
DISPLAY 0.617021 (-1375 2135);
PAINT PINK (-1375 2135);
FORCEPROP 2 LAST CDS_LIB mstr_standard
J 0
(-1375 2125);
DISPLAY 0.787234 (-1375 2125);
PAINT MONO (-1375 2125);
DISPLAY INVISIBLE (-1375 2125);
FORCEPROP 1 LAST BODY_TYPE PLUMBING
J 0
(-1375 2075);
DISPLAY 1.234043 (-1375 2075);
PAINT GREEN (-1375 2075);
DISPLAY INVISIBLE (-1375 2075);
FORCEPROP 1 LAST HDL_TAP TRUE
J 0
(-1050 2000);
DISPLAY 1.234043 (-1050 2000);
PAINT GREEN (-1050 2000);
DISPLAY INVISIBLE (-1050 2000);
FORCEPROP 1 LAST PATH I27
J 0
(-1377 2125);
DISPLAY 0.872340 (-1377 2125);
PAINT GREEN (-1377 2125);
DISPLAY INVISIBLE (-1377 2125);
FORCEADD TAP..6
(-1375 2325);
FORCEPROP 3 LASTPIN (-1325 2325) SIG_NAME M_G_ODT<3>
J 0
(-1315 2335);
DISPLAY 0.659574 (-1315 2335);
PAINT MONO (-1315 2335);
DISPLAY INVISIBLE (-1315 2335);
FORCEPROP 1 LASTPIN (-1325 2325) BN 3
J 0
(-1375 2335);
DISPLAY 0.617021 (-1375 2335);
PAINT PINK (-1375 2335);
FORCEPROP 2 LAST CDS_LIB mstr_standard
J 0
(-1375 2325);
DISPLAY 0.787234 (-1375 2325);
PAINT MONO (-1375 2325);
DISPLAY INVISIBLE (-1375 2325);
FORCEPROP 1 LAST BODY_TYPE PLUMBING
J 0
(-1375 2275);
DISPLAY 1.234043 (-1375 2275);
PAINT GREEN (-1375 2275);
DISPLAY INVISIBLE (-1375 2275);
FORCEPROP 1 LAST HDL_TAP TRUE
J 0
(-1050 2200);
DISPLAY 1.234043 (-1050 2200);
PAINT GREEN (-1050 2200);
DISPLAY INVISIBLE (-1050 2200);
FORCEPROP 1 LAST PATH I28
J 0
(-1377 2325);
DISPLAY 0.872340 (-1377 2325);
PAINT GREEN (-1377 2325);
DISPLAY INVISIBLE (-1377 2325);
FORCEADD TAP..6
(-1375 2275);
FORCEPROP 3 LASTPIN (-1325 2275) SIG_NAME M_G_ODT<2>
J 0
(-1315 2285);
DISPLAY 0.659574 (-1315 2285);
PAINT MONO (-1315 2285);
DISPLAY INVISIBLE (-1315 2285);
FORCEPROP 1 LASTPIN (-1325 2275) BN 2
J 0
(-1375 2285);
DISPLAY 0.617021 (-1375 2285);
PAINT PINK (-1375 2285);
FORCEPROP 2 LAST CDS_LIB mstr_standard
J 0
(-1375 2275);
DISPLAY 0.787234 (-1375 2275);
PAINT MONO (-1375 2275);
DISPLAY INVISIBLE (-1375 2275);
FORCEPROP 1 LAST BODY_TYPE PLUMBING
J 0
(-1375 2225);
DISPLAY 1.234043 (-1375 2225);
PAINT GREEN (-1375 2225);
DISPLAY INVISIBLE (-1375 2225);
FORCEPROP 1 LAST HDL_TAP TRUE
J 0
(-1050 2150);
DISPLAY 1.234043 (-1050 2150);
PAINT GREEN (-1050 2150);
DISPLAY INVISIBLE (-1050 2150);
FORCEPROP 1 LAST PATH I29
J 0
(-1377 2275);
DISPLAY 0.872340 (-1377 2275);
PAINT GREEN (-1377 2275);
DISPLAY INVISIBLE (-1377 2275);
FORCEADD GND..1
R 2
(-3325 1225);
FORCEPROP 3 LASTPIN (-3325 1275) SIG_NAME GND\g
J 0
(-3315 1285);
DISPLAY 0.659574 (-3315 1285);
PAINT MONO (-3315 1285);
DISPLAY INVISIBLE (-3315 1285);
FORCEPROP 1 LAST VOLTAGE 0.0V
J 2
(-3280 1182);
DISPLAY 0.340426 (-3280 1182);
PAINT SKYBLUE (-3280 1182);
DISPLAY INVISIBLE (-3280 1182);
FORCEPROP 1 LAST SIZE 1B
J 2
(-3400 1175);
DISPLAY 1.170213 (-3400 1175);
PAINT GREEN (-3400 1175);
DISPLAY INVISIBLE (-3400 1175);
FORCEPROP 2 LAST CDS_LIB mstr_symbols
J 0
(-3325 1225);
DISPLAY 0.787234 (-3325 1225);
PAINT MONO (-3325 1225);
DISPLAY INVISIBLE (-3325 1225);
FORCEPROP 2 LAST BOM_COST MEM
J 0
(-3325 1230);
PAINT ORANGE (-3325 1230);
DISPLAY INVISIBLE (-3325 1230);
FORCEPROP 1 LAST BODY_TYPE PLUMBING
J 2
(-3280 1182);
DISPLAY 0.340426 (-3280 1182);
PAINT GREEN (-3280 1182);
DISPLAY INVISIBLE (-3280 1182);
FORCEPROP 1 LAST PATH I3
J 2
(-3400 1225);
DISPLAY 0.872340 (-3400 1225);
PAINT AQUA (-3400 1225);
DISPLAY INVISIBLE (-3400 1225);
FORCEPROP 2 LAST ROOM DDR4_GH_G
J 0
(-3325 1230);
PAINT ORANGE (-3325 1230);
DISPLAY INVISIBLE (-3325 1230);
FORCEPROP 1 LAST HDL_POWER GND
J 2
(-3325 1375);
DISPLAY 0.553191 (-3325 1375);
PAINT GREEN (-3325 1375);
DISPLAY INVISIBLE (-3325 1375);
FORCEADD TAP..6
(-1375 2425);
FORCEPROP 3 LASTPIN (-1325 2425) SIG_NAME M_G_CKE<2>
J 0
(-1315 2435);
DISPLAY 0.659574 (-1315 2435);
PAINT MONO (-1315 2435);
DISPLAY INVISIBLE (-1315 2435);
FORCEPROP 1 LASTPIN (-1325 2425) BN 2
J 0
(-1375 2435);
DISPLAY 0.617021 (-1375 2435);
PAINT PINK (-1375 2435);
FORCEPROP 2 LAST CDS_LIB mstr_standard
J 0
(-1375 2425);
DISPLAY 0.787234 (-1375 2425);
PAINT MONO (-1375 2425);
DISPLAY INVISIBLE (-1375 2425);
FORCEPROP 1 LAST BODY_TYPE PLUMBING
J 0
(-1375 2375);
DISPLAY 1.234043 (-1375 2375);
PAINT GREEN (-1375 2375);
DISPLAY INVISIBLE (-1375 2375);
FORCEPROP 1 LAST HDL_TAP TRUE
J 0
(-1050 2300);
DISPLAY 1.234043 (-1050 2300);
PAINT GREEN (-1050 2300);
DISPLAY INVISIBLE (-1050 2300);
FORCEPROP 1 LAST PATH I30
J 0
(-1377 2425);
DISPLAY 0.872340 (-1377 2425);
PAINT GREEN (-1377 2425);
DISPLAY INVISIBLE (-1377 2425);
FORCEADD TAP..6
(-1375 2475);
FORCEPROP 3 LASTPIN (-1325 2475) SIG_NAME M_G_CKE<3>
J 0
(-1315 2485);
DISPLAY 0.659574 (-1315 2485);
PAINT MONO (-1315 2485);
DISPLAY INVISIBLE (-1315 2485);
FORCEPROP 1 LASTPIN (-1325 2475) BN 3
J 0
(-1375 2485);
DISPLAY 0.617021 (-1375 2485);
PAINT PINK (-1375 2485);
FORCEPROP 2 LAST CDS_LIB mstr_standard
J 0
(-1375 2475);
DISPLAY 0.787234 (-1375 2475);
PAINT MONO (-1375 2475);
DISPLAY INVISIBLE (-1375 2475);
FORCEPROP 1 LAST BODY_TYPE PLUMBING
J 0
(-1375 2425);
DISPLAY 1.234043 (-1375 2425);
PAINT GREEN (-1375 2425);
DISPLAY INVISIBLE (-1375 2425);
FORCEPROP 1 LAST HDL_TAP TRUE
J 0
(-1050 2350);
DISPLAY 1.234043 (-1050 2350);
PAINT GREEN (-1050 2350);
DISPLAY INVISIBLE (-1050 2350);
FORCEPROP 1 LAST PATH I31
J 0
(-1377 2475);
DISPLAY 0.872340 (-1377 2475);
PAINT GREEN (-1377 2475);
DISPLAY INVISIBLE (-1377 2475);
FORCEADD TAP..6
(-1375 2575);
FORCEPROP 3 LASTPIN (-1325 2575) SIG_NAME M_G_CS_N<4>
J 0
(-1315 2585);
DISPLAY 0.659574 (-1315 2585);
PAINT MONO (-1315 2585);
DISPLAY INVISIBLE (-1315 2585);
FORCEPROP 1 LASTPIN (-1325 2575) BN 4
J 0
(-1375 2585);
DISPLAY 0.617021 (-1375 2585);
PAINT PINK (-1375 2585);
FORCEPROP 2 LAST CDS_LIB mstr_standard
J 0
(-1375 2575);
DISPLAY 0.787234 (-1375 2575);
PAINT MONO (-1375 2575);
DISPLAY INVISIBLE (-1375 2575);
FORCEPROP 1 LAST BODY_TYPE PLUMBING
J 0
(-1375 2525);
DISPLAY 1.234043 (-1375 2525);
PAINT GREEN (-1375 2525);
DISPLAY INVISIBLE (-1375 2525);
FORCEPROP 1 LAST HDL_TAP TRUE
J 0
(-1050 2450);
DISPLAY 1.234043 (-1050 2450);
PAINT GREEN (-1050 2450);
DISPLAY INVISIBLE (-1050 2450);
FORCEPROP 1 LAST PATH I32
J 0
(-1377 2575);
DISPLAY 0.872340 (-1377 2575);
PAINT GREEN (-1377 2575);
DISPLAY INVISIBLE (-1377 2575);
FORCEADD TAP..6
(-1375 2675);
FORCEPROP 3 LASTPIN (-1325 2675) SIG_NAME M_G_CS_N<6>
J 0
(-1315 2685);
DISPLAY 0.659574 (-1315 2685);
PAINT MONO (-1315 2685);
DISPLAY INVISIBLE (-1315 2685);
FORCEPROP 1 LASTPIN (-1325 2675) BN 6
J 0
(-1375 2685);
DISPLAY 0.617021 (-1375 2685);
PAINT PINK (-1375 2685);
FORCEPROP 2 LAST CDS_LIB mstr_standard
J 0
(-1375 2675);
DISPLAY 0.787234 (-1375 2675);
PAINT MONO (-1375 2675);
DISPLAY INVISIBLE (-1375 2675);
FORCEPROP 1 LAST BODY_TYPE PLUMBING
J 0
(-1375 2625);
DISPLAY 1.234043 (-1375 2625);
PAINT GREEN (-1375 2625);
DISPLAY INVISIBLE (-1375 2625);
FORCEPROP 1 LAST HDL_TAP TRUE
J 0
(-1050 2550);
DISPLAY 1.234043 (-1050 2550);
PAINT GREEN (-1050 2550);
DISPLAY INVISIBLE (-1050 2550);
FORCEPROP 1 LAST PATH I33
J 0
(-1377 2675);
DISPLAY 0.872340 (-1377 2675);
PAINT GREEN (-1377 2675);
DISPLAY INVISIBLE (-1377 2675);
FORCEADD TAP..6
(-1375 2625);
FORCEPROP 3 LASTPIN (-1325 2625) SIG_NAME M_G_CS_N<5>
J 0
(-1315 2635);
DISPLAY 0.659574 (-1315 2635);
PAINT MONO (-1315 2635);
DISPLAY INVISIBLE (-1315 2635);
FORCEPROP 1 LASTPIN (-1325 2625) BN 5
J 0
(-1375 2635);
DISPLAY 0.617021 (-1375 2635);
PAINT PINK (-1375 2635);
FORCEPROP 2 LAST CDS_LIB mstr_standard
J 0
(-1375 2625);
DISPLAY 0.787234 (-1375 2625);
PAINT MONO (-1375 2625);
DISPLAY INVISIBLE (-1375 2625);
FORCEPROP 1 LAST BODY_TYPE PLUMBING
J 0
(-1375 2575);
DISPLAY 1.234043 (-1375 2575);
PAINT GREEN (-1375 2575);
DISPLAY INVISIBLE (-1375 2575);
FORCEPROP 1 LAST HDL_TAP TRUE
J 0
(-1050 2500);
DISPLAY 1.234043 (-1050 2500);
PAINT GREEN (-1050 2500);
DISPLAY INVISIBLE (-1050 2500);
FORCEPROP 1 LAST PATH I34
J 0
(-1377 2625);
DISPLAY 0.872340 (-1377 2625);
PAINT GREEN (-1377 2625);
DISPLAY INVISIBLE (-1377 2625);
FORCEADD TAP..6
(-1375 2725);
FORCEPROP 3 LASTPIN (-1325 2725) SIG_NAME M_G_CS_N<7>
J 0
(-1315 2735);
DISPLAY 0.659574 (-1315 2735);
PAINT MONO (-1315 2735);
DISPLAY INVISIBLE (-1315 2735);
FORCEPROP 1 LASTPIN (-1325 2725) BN 7
J 0
(-1375 2735);
DISPLAY 0.617021 (-1375 2735);
PAINT PINK (-1375 2735);
FORCEPROP 2 LAST CDS_LIB mstr_standard
J 0
(-1375 2725);
DISPLAY 0.787234 (-1375 2725);
PAINT MONO (-1375 2725);
DISPLAY INVISIBLE (-1375 2725);
FORCEPROP 1 LAST BODY_TYPE PLUMBING
J 0
(-1375 2675);
DISPLAY 1.234043 (-1375 2675);
PAINT GREEN (-1375 2675);
DISPLAY INVISIBLE (-1375 2675);
FORCEPROP 1 LAST HDL_TAP TRUE
J 0
(-1050 2600);
DISPLAY 1.234043 (-1050 2600);
PAINT GREEN (-1050 2600);
DISPLAY INVISIBLE (-1050 2600);
FORCEPROP 1 LAST PATH I35
J 0
(-1377 2725);
DISPLAY 0.872340 (-1377 2725);
PAINT GREEN (-1377 2725);
DISPLAY INVISIBLE (-1377 2725);
FORCEADD OFFPAGE..1
(-2025 3050);
FORCEPROP 2 LAST $XR1 77 
J 0
(-2336 3050);
DISPLAY 0.638298 (-2336 3050);
PAINT MONO (-2336 3050);
FORCEPROP 2 LAST $XR0 57 
J 0
(-2246 3050);
DISPLAY 0.638298 (-2246 3050);
PAINT MONO (-2246 3050);
FORCEPROP 2 LAST CDS_LIB mstr_standard
J 0
(-2025 3050);
DISPLAY 0.787234 (-2025 3050);
PAINT MONO (-2025 3050);
DISPLAY INVISIBLE (-2025 3050);
FORCEPROP 1 LAST OFFPAGE TRUE
J 0
(-1700 2925);
DISPLAY 0.936170 (-1700 2925);
PAINT GREEN (-1700 2925);
DISPLAY INVISIBLE (-1700 2925);
FORCEPROP 1 LAST COMMENT_BODY TRUE
J 0
(-1900 2950);
DISPLAY 0.936170 (-1900 2950);
PAINT GREEN (-1900 2950);
DISPLAY INVISIBLE (-1900 2950);
FORCEPROP 2 LAST PATH I36
J 0
(-2225 3100);
DISPLAY 1.021277 (-2225 3100);
PAINT ORANGE (-2225 3100);
DISPLAY INVISIBLE (-2225 3100);
FORCEADD OFFPAGE..1
(-2025 3100);
FORCEPROP 2 LAST $XR1 77 
J 0
(-2336 3100);
DISPLAY 0.638298 (-2336 3100);
PAINT MONO (-2336 3100);
FORCEPROP 2 LAST $XR0 57 
J 0
(-2246 3100);
DISPLAY 0.638298 (-2246 3100);
PAINT MONO (-2246 3100);
FORCEPROP 2 LAST CDS_LIB mstr_standard
J 0
(-2025 3100);
DISPLAY 0.787234 (-2025 3100);
PAINT MONO (-2025 3100);
DISPLAY INVISIBLE (-2025 3100);
FORCEPROP 1 LAST OFFPAGE TRUE
J 0
(-1700 2975);
DISPLAY 0.936170 (-1700 2975);
PAINT GREEN (-1700 2975);
DISPLAY INVISIBLE (-1700 2975);
FORCEPROP 1 LAST COMMENT_BODY TRUE
J 0
(-1900 3000);
DISPLAY 0.936170 (-1900 3000);
PAINT GREEN (-1900 3000);
DISPLAY INVISIBLE (-1900 3000);
FORCEPROP 2 LAST PATH I37
J 0
(-2225 3150);
DISPLAY 1.021277 (-2225 3150);
PAINT ORANGE (-2225 3150);
DISPLAY INVISIBLE (-2225 3150);
FORCEADD OFFPAGE..1
(-2025 3225);
FORCEPROP 2 LAST $XR1 77 
J 0
(-2336 3225);
DISPLAY 0.638298 (-2336 3225);
PAINT MONO (-2336 3225);
FORCEPROP 2 LAST $XR0 57 
J 0
(-2246 3225);
DISPLAY 0.638298 (-2246 3225);
PAINT MONO (-2246 3225);
FORCEPROP 2 LAST CDS_LIB mstr_standard
J 0
(-2025 3225);
DISPLAY 0.787234 (-2025 3225);
PAINT MONO (-2025 3225);
DISPLAY INVISIBLE (-2025 3225);
FORCEPROP 1 LAST OFFPAGE TRUE
J 0
(-1700 3100);
DISPLAY 0.936170 (-1700 3100);
PAINT GREEN (-1700 3100);
DISPLAY INVISIBLE (-1700 3100);
FORCEPROP 1 LAST COMMENT_BODY TRUE
J 0
(-1900 3125);
DISPLAY 0.936170 (-1900 3125);
PAINT GREEN (-1900 3125);
DISPLAY INVISIBLE (-1900 3125);
FORCEPROP 2 LAST PATH I38
J 0
(-2225 3275);
DISPLAY 1.021277 (-2225 3275);
PAINT ORANGE (-2225 3275);
DISPLAY INVISIBLE (-2225 3275);
FORCEADD OFFPAGE..1
(-2025 3350);
FORCEPROP 2 LAST $XR1 77 
J 0
(-2336 3350);
DISPLAY 0.638298 (-2336 3350);
PAINT MONO (-2336 3350);
FORCEPROP 2 LAST $XR0 57 
J 0
(-2246 3350);
DISPLAY 0.638298 (-2246 3350);
PAINT MONO (-2246 3350);
FORCEPROP 2 LAST CDS_LIB mstr_standard
J 0
(-2025 3350);
DISPLAY 0.787234 (-2025 3350);
PAINT MONO (-2025 3350);
DISPLAY INVISIBLE (-2025 3350);
FORCEPROP 1 LAST OFFPAGE TRUE
J 0
(-1700 3225);
DISPLAY 0.936170 (-1700 3225);
PAINT GREEN (-1700 3225);
DISPLAY INVISIBLE (-1700 3225);
FORCEPROP 1 LAST COMMENT_BODY TRUE
J 0
(-1900 3250);
DISPLAY 0.936170 (-1900 3250);
PAINT GREEN (-1900 3250);
DISPLAY INVISIBLE (-1900 3250);
FORCEPROP 2 LAST PATH I39
J 0
(-2225 3400);
DISPLAY 1.021277 (-2225 3400);
PAINT ORANGE (-2225 3400);
DISPLAY INVISIBLE (-2225 3400);
FORCEADD OFFPAGE..1
(-2825 1075);
FORCEPROP 2 LAST $XR1 77 
J 0
(-3167 1075);
DISPLAY 0.638298 (-3167 1075);
PAINT MONO (-3167 1075);
FORCEPROP 2 LAST $XR0 100 
J 0
(-3077 1075);
DISPLAY 0.638298 (-3077 1075);
PAINT MONO (-3077 1075);
FORCEPROP 2 LAST CDS_LIB mstr_standard
J 0
(-2825 1075);
DISPLAY 0.787234 (-2825 1075);
PAINT MONO (-2825 1075);
DISPLAY INVISIBLE (-2825 1075);
FORCEPROP 1 LAST OFFPAGE TRUE
J 0
(-2500 950);
DISPLAY 0.936170 (-2500 950);
PAINT GREEN (-2500 950);
DISPLAY INVISIBLE (-2500 950);
FORCEPROP 1 LAST COMMENT_BODY TRUE
J 0
(-2700 975);
DISPLAY 0.936170 (-2700 975);
PAINT GREEN (-2700 975);
DISPLAY INVISIBLE (-2700 975);
FORCEPROP 2 LAST PATH I4
J 0
(-3025 1125);
DISPLAY 1.021277 (-3025 1125);
PAINT ORANGE (-3025 1125);
DISPLAY INVISIBLE (-3025 1125);
FORCEADD TAP..6
(-1575 2975);
FORCEPROP 3 LASTPIN (-1525 2975) SIG_NAME M_G_CLK_DN<3>
J 0
(-1515 2985);
DISPLAY 0.659574 (-1515 2985);
PAINT MONO (-1515 2985);
DISPLAY INVISIBLE (-1515 2985);
FORCEPROP 1 LASTPIN (-1525 2975) BN 3
J 0
(-1575 2985);
DISPLAY 0.617021 (-1575 2985);
PAINT PINK (-1575 2985);
FORCEPROP 2 LAST CDS_LIB mstr_standard
J 0
(-1575 2975);
DISPLAY 0.787234 (-1575 2975);
PAINT MONO (-1575 2975);
DISPLAY INVISIBLE (-1575 2975);
FORCEPROP 1 LAST BODY_TYPE PLUMBING
J 0
(-1575 2925);
DISPLAY 1.234043 (-1575 2925);
PAINT GREEN (-1575 2925);
DISPLAY INVISIBLE (-1575 2925);
FORCEPROP 1 LAST HDL_TAP TRUE
J 0
(-1250 2850);
DISPLAY 1.234043 (-1250 2850);
PAINT GREEN (-1250 2850);
DISPLAY INVISIBLE (-1250 2850);
FORCEPROP 1 LAST PATH I40
J 0
(-1577 2975);
DISPLAY 0.872340 (-1577 2975);
PAINT GREEN (-1577 2975);
DISPLAY INVISIBLE (-1577 2975);
FORCEADD TAP..6
(-1575 2875);
FORCEPROP 3 LASTPIN (-1525 2875) SIG_NAME M_G_CLK_DN<2>
J 0
(-1515 2885);
DISPLAY 0.659574 (-1515 2885);
PAINT MONO (-1515 2885);
DISPLAY INVISIBLE (-1515 2885);
FORCEPROP 1 LASTPIN (-1525 2875) BN 2
J 0
(-1575 2885);
DISPLAY 0.617021 (-1575 2885);
PAINT PINK (-1575 2885);
FORCEPROP 2 LAST CDS_LIB mstr_standard
J 0
(-1575 2875);
DISPLAY 0.787234 (-1575 2875);
PAINT MONO (-1575 2875);
DISPLAY INVISIBLE (-1575 2875);
FORCEPROP 1 LAST BODY_TYPE PLUMBING
J 0
(-1575 2825);
DISPLAY 1.234043 (-1575 2825);
PAINT GREEN (-1575 2825);
DISPLAY INVISIBLE (-1575 2825);
FORCEPROP 1 LAST HDL_TAP TRUE
J 0
(-1250 2750);
DISPLAY 1.234043 (-1250 2750);
PAINT GREEN (-1250 2750);
DISPLAY INVISIBLE (-1250 2750);
FORCEPROP 1 LAST PATH I41
J 0
(-1577 2875);
DISPLAY 0.872340 (-1577 2875);
PAINT GREEN (-1577 2875);
DISPLAY INVISIBLE (-1577 2875);
FORCEADD TAP..6
(-1375 2925);
FORCEPROP 3 LASTPIN (-1325 2925) SIG_NAME M_G_CLK_DP<2>
J 0
(-1315 2935);
DISPLAY 0.659574 (-1315 2935);
PAINT MONO (-1315 2935);
DISPLAY INVISIBLE (-1315 2935);
FORCEPROP 1 LASTPIN (-1325 2925) BN 2
J 0
(-1375 2935);
DISPLAY 0.617021 (-1375 2935);
PAINT PINK (-1375 2935);
FORCEPROP 2 LAST CDS_LIB mstr_standard
J 0
(-1375 2925);
DISPLAY 0.787234 (-1375 2925);
PAINT MONO (-1375 2925);
DISPLAY INVISIBLE (-1375 2925);
FORCEPROP 1 LAST BODY_TYPE PLUMBING
J 0
(-1375 2875);
DISPLAY 1.234043 (-1375 2875);
PAINT GREEN (-1375 2875);
DISPLAY INVISIBLE (-1375 2875);
FORCEPROP 1 LAST HDL_TAP TRUE
J 0
(-1050 2800);
DISPLAY 1.234043 (-1050 2800);
PAINT GREEN (-1050 2800);
DISPLAY INVISIBLE (-1050 2800);
FORCEPROP 1 LAST PATH I42
J 0
(-1377 2925);
DISPLAY 0.872340 (-1377 2925);
PAINT GREEN (-1377 2925);
DISPLAY INVISIBLE (-1377 2925);
FORCEADD TAP..6
(-1375 3025);
FORCEPROP 3 LASTPIN (-1325 3025) SIG_NAME M_G_CLK_DP<3>
J 0
(-1315 3035);
DISPLAY 0.659574 (-1315 3035);
PAINT MONO (-1315 3035);
DISPLAY INVISIBLE (-1315 3035);
FORCEPROP 1 LASTPIN (-1325 3025) BN 3
J 0
(-1375 3035);
DISPLAY 0.617021 (-1375 3035);
PAINT PINK (-1375 3035);
FORCEPROP 2 LAST CDS_LIB mstr_standard
J 0
(-1375 3025);
DISPLAY 0.787234 (-1375 3025);
PAINT MONO (-1375 3025);
DISPLAY INVISIBLE (-1375 3025);
FORCEPROP 1 LAST BODY_TYPE PLUMBING
J 0
(-1375 2975);
DISPLAY 1.234043 (-1375 2975);
PAINT GREEN (-1375 2975);
DISPLAY INVISIBLE (-1375 2975);
FORCEPROP 1 LAST HDL_TAP TRUE
J 0
(-1050 2900);
DISPLAY 1.234043 (-1050 2900);
PAINT GREEN (-1050 2900);
DISPLAY INVISIBLE (-1050 2900);
FORCEPROP 1 LAST PATH I43
J 0
(-1377 3025);
DISPLAY 0.872340 (-1377 3025);
PAINT GREEN (-1377 3025);
DISPLAY INVISIBLE (-1377 3025);
FORCEADD TAP..6
(-1375 3125);
FORCEPROP 3 LASTPIN (-1325 3125) SIG_NAME M_G_BG<0>
J 0
(-1315 3135);
DISPLAY 0.659574 (-1315 3135);
PAINT MONO (-1315 3135);
DISPLAY INVISIBLE (-1315 3135);
FORCEPROP 1 LASTPIN (-1325 3125) BN 0
J 0
(-1375 3135);
DISPLAY 0.617021 (-1375 3135);
PAINT PINK (-1375 3135);
FORCEPROP 2 LAST CDS_LIB mstr_standard
J 0
(-1375 3125);
DISPLAY 0.787234 (-1375 3125);
PAINT MONO (-1375 3125);
DISPLAY INVISIBLE (-1375 3125);
FORCEPROP 1 LAST BODY_TYPE PLUMBING
J 0
(-1375 3075);
DISPLAY 1.234043 (-1375 3075);
PAINT GREEN (-1375 3075);
DISPLAY INVISIBLE (-1375 3075);
FORCEPROP 1 LAST HDL_TAP TRUE
J 0
(-1050 3000);
DISPLAY 1.234043 (-1050 3000);
PAINT GREEN (-1050 3000);
DISPLAY INVISIBLE (-1050 3000);
FORCEPROP 1 LAST PATH I44
J 0
(-1377 3125);
DISPLAY 0.872340 (-1377 3125);
PAINT GREEN (-1377 3125);
DISPLAY INVISIBLE (-1377 3125);
FORCEADD TAP..6
(-1375 3225);
FORCEPROP 3 LASTPIN (-1325 3225) SIG_NAME M_G_BA<0>
J 0
(-1315 3235);
DISPLAY 0.659574 (-1315 3235);
PAINT MONO (-1315 3235);
DISPLAY INVISIBLE (-1315 3235);
FORCEPROP 1 LASTPIN (-1325 3225) BN 0
J 0
(-1375 3235);
DISPLAY 0.617021 (-1375 3235);
PAINT PINK (-1375 3235);
FORCEPROP 2 LAST CDS_LIB mstr_standard
J 0
(-1375 3225);
DISPLAY 0.787234 (-1375 3225);
PAINT MONO (-1375 3225);
DISPLAY INVISIBLE (-1375 3225);
FORCEPROP 1 LAST BODY_TYPE PLUMBING
J 0
(-1375 3175);
DISPLAY 1.234043 (-1375 3175);
PAINT GREEN (-1375 3175);
DISPLAY INVISIBLE (-1375 3175);
FORCEPROP 1 LAST HDL_TAP TRUE
J 0
(-1050 3100);
DISPLAY 1.234043 (-1050 3100);
PAINT GREEN (-1050 3100);
DISPLAY INVISIBLE (-1050 3100);
FORCEPROP 1 LAST PATH I45
J 0
(-1377 3225);
DISPLAY 0.872340 (-1377 3225);
PAINT GREEN (-1377 3225);
DISPLAY INVISIBLE (-1377 3225);
FORCEADD TAP..6
(-1375 3175);
FORCEPROP 3 LASTPIN (-1325 3175) SIG_NAME M_G_BG<1>
J 0
(-1315 3185);
DISPLAY 0.659574 (-1315 3185);
PAINT MONO (-1315 3185);
DISPLAY INVISIBLE (-1315 3185);
FORCEPROP 1 LASTPIN (-1325 3175) BN 1
J 0
(-1375 3185);
DISPLAY 0.617021 (-1375 3185);
PAINT PINK (-1375 3185);
FORCEPROP 2 LAST CDS_LIB mstr_standard
J 0
(-1375 3175);
DISPLAY 0.787234 (-1375 3175);
PAINT MONO (-1375 3175);
DISPLAY INVISIBLE (-1375 3175);
FORCEPROP 1 LAST BODY_TYPE PLUMBING
J 0
(-1375 3125);
DISPLAY 1.234043 (-1375 3125);
PAINT GREEN (-1375 3125);
DISPLAY INVISIBLE (-1375 3125);
FORCEPROP 1 LAST HDL_TAP TRUE
J 0
(-1050 3050);
DISPLAY 1.234043 (-1050 3050);
PAINT GREEN (-1050 3050);
DISPLAY INVISIBLE (-1050 3050);
FORCEPROP 1 LAST PATH I46
J 0
(-1377 3175);
DISPLAY 0.872340 (-1377 3175);
PAINT GREEN (-1377 3175);
DISPLAY INVISIBLE (-1377 3175);
FORCEADD TAP..6
(-1375 3275);
FORCEPROP 3 LASTPIN (-1325 3275) SIG_NAME M_G_BA<1>
J 0
(-1315 3285);
DISPLAY 0.659574 (-1315 3285);
PAINT MONO (-1315 3285);
DISPLAY INVISIBLE (-1315 3285);
FORCEPROP 1 LASTPIN (-1325 3275) BN 1
J 0
(-1375 3285);
DISPLAY 0.617021 (-1375 3285);
PAINT PINK (-1375 3285);
FORCEPROP 2 LAST CDS_LIB mstr_standard
J 0
(-1375 3275);
DISPLAY 0.787234 (-1375 3275);
PAINT MONO (-1375 3275);
DISPLAY INVISIBLE (-1375 3275);
FORCEPROP 1 LAST BODY_TYPE PLUMBING
J 0
(-1375 3225);
DISPLAY 1.234043 (-1375 3225);
PAINT GREEN (-1375 3225);
DISPLAY INVISIBLE (-1375 3225);
FORCEPROP 1 LAST HDL_TAP TRUE
J 0
(-1050 3150);
DISPLAY 1.234043 (-1050 3150);
PAINT GREEN (-1050 3150);
DISPLAY INVISIBLE (-1050 3150);
FORCEPROP 1 LAST PATH I47
J 0
(-1377 3275);
DISPLAY 0.872340 (-1377 3275);
PAINT GREEN (-1377 3275);
DISPLAY INVISIBLE (-1377 3275);
FORCEADD TAP..6
(-1375 3375);
FORCEPROP 3 LASTPIN (-1325 3375) SIG_NAME M_G_MA<0>
J 0
(-1315 3385);
DISPLAY 0.659574 (-1315 3385);
PAINT MONO (-1315 3385);
DISPLAY INVISIBLE (-1315 3385);
FORCEPROP 1 LASTPIN (-1325 3375) BN 0
J 0
(-1375 3385);
DISPLAY 0.617021 (-1375 3385);
PAINT PINK (-1375 3385);
FORCEPROP 2 LAST CDS_LIB mstr_standard
J 2
(-1375 3375);
DISPLAY 0.787234 (-1375 3375);
PAINT MONO (-1375 3375);
DISPLAY INVISIBLE (-1375 3375);
FORCEPROP 1 LAST BODY_TYPE PLUMBING
J 0
(-1375 3325);
DISPLAY 1.234043 (-1375 3325);
PAINT GREEN (-1375 3325);
DISPLAY INVISIBLE (-1375 3325);
FORCEPROP 1 LAST HDL_TAP TRUE
J 0
(-1050 3250);
DISPLAY 1.234043 (-1050 3250);
PAINT GREEN (-1050 3250);
DISPLAY INVISIBLE (-1050 3250);
FORCEPROP 1 LAST PATH I48
J 0
(-1377 3375);
DISPLAY 0.872340 (-1377 3375);
PAINT GREEN (-1377 3375);
DISPLAY INVISIBLE (-1377 3375);
FORCEADD TAP..6
(-1375 3475);
FORCEPROP 3 LASTPIN (-1325 3475) SIG_NAME M_G_MA<2>
J 0
(-1315 3485);
DISPLAY 0.659574 (-1315 3485);
PAINT MONO (-1315 3485);
DISPLAY INVISIBLE (-1315 3485);
FORCEPROP 1 LASTPIN (-1325 3475) BN 2
J 0
(-1375 3485);
DISPLAY 0.617021 (-1375 3485);
PAINT PINK (-1375 3485);
FORCEPROP 2 LAST CDS_LIB mstr_standard
J 2
(-1375 3475);
DISPLAY 0.787234 (-1375 3475);
PAINT MONO (-1375 3475);
DISPLAY INVISIBLE (-1375 3475);
FORCEPROP 1 LAST BODY_TYPE PLUMBING
J 0
(-1375 3425);
DISPLAY 1.234043 (-1375 3425);
PAINT GREEN (-1375 3425);
DISPLAY INVISIBLE (-1375 3425);
FORCEPROP 1 LAST HDL_TAP TRUE
J 0
(-1050 3350);
DISPLAY 1.234043 (-1050 3350);
PAINT GREEN (-1050 3350);
DISPLAY INVISIBLE (-1050 3350);
FORCEPROP 1 LAST PATH I49
J 0
(-1377 3475);
DISPLAY 0.872340 (-1377 3475);
PAINT GREEN (-1377 3475);
DISPLAY INVISIBLE (-1377 3475);
FORCEADD PVPP_GHJ..1
(-3325 1575);
FORCEPROP 3 LASTPIN (-3325 1525) SIG_NAME PVPP_GHJ\g
J 0
(-3315 1535);
DISPLAY 0.659574 (-3315 1535);
PAINT MONO (-3315 1535);
DISPLAY INVISIBLE (-3315 1535);
FORCEPROP 1 LAST VOLTAGE 2.5V
J 0
(-3370 1532);
DISPLAY 0.340426 (-3370 1532);
PAINT SKYBLUE (-3370 1532);
DISPLAY INVISIBLE (-3370 1532);
FORCEPROP 0 LAST BOM_COST MEM
J 0
(-3325 1675);
PAINT ORANGE (-3325 1675);
DISPLAY INVISIBLE (-3325 1675);
FORCEPROP 2 LAST CDS_LIB mstr_symbols
J 0
(-3325 1575);
PAINT ORANGE (-3325 1575);
DISPLAY INVISIBLE (-3325 1575);
FORCEPROP 1 LAST BODY_TYPE PLUMBING
J 0
(-3370 1532);
DISPLAY 0.340426 (-3370 1532);
PAINT GREEN (-3370 1532);
DISPLAY INVISIBLE (-3370 1532);
FORCEPROP 1 LAST PATH I5
J 0
(-3275 1600);
DISPLAY 0.872340 (-3275 1600);
PAINT AQUA (-3275 1600);
DISPLAY INVISIBLE (-3275 1600);
FORCEPROP 2 LAST ROOM DDR4_GH_G
J 0
(-3325 1675);
PAINT ORANGE (-3325 1675);
DISPLAY INVISIBLE (-3325 1675);
FORCEPROP 1 LAST HDL_POWER PVPP_GHJ
J 1
(-3325 1625);
DISPLAY 0.872340 (-3325 1625);
PAINT GREEN (-3325 1625);
DISPLAY INVISIBLE (-3325 1625);
FORCEADD TAP..6
(-1375 3425);
FORCEPROP 3 LASTPIN (-1325 3425) SIG_NAME M_G_MA<1>
J 0
(-1315 3435);
DISPLAY 0.659574 (-1315 3435);
PAINT MONO (-1315 3435);
DISPLAY INVISIBLE (-1315 3435);
FORCEPROP 1 LASTPIN (-1325 3425) BN 1
J 0
(-1375 3435);
DISPLAY 0.617021 (-1375 3435);
PAINT PINK (-1375 3435);
FORCEPROP 2 LAST CDS_LIB mstr_standard
J 2
(-1375 3425);
DISPLAY 0.787234 (-1375 3425);
PAINT MONO (-1375 3425);
DISPLAY INVISIBLE (-1375 3425);
FORCEPROP 1 LAST BODY_TYPE PLUMBING
J 0
(-1375 3375);
DISPLAY 1.234043 (-1375 3375);
PAINT GREEN (-1375 3375);
DISPLAY INVISIBLE (-1375 3375);
FORCEPROP 1 LAST HDL_TAP TRUE
J 0
(-1050 3300);
DISPLAY 1.234043 (-1050 3300);
PAINT GREEN (-1050 3300);
DISPLAY INVISIBLE (-1050 3300);
FORCEPROP 1 LAST PATH I50
J 0
(-1377 3425);
DISPLAY 0.872340 (-1377 3425);
PAINT GREEN (-1377 3425);
DISPLAY INVISIBLE (-1377 3425);
FORCEADD TAP..6
(-1375 3575);
FORCEPROP 3 LASTPIN (-1325 3575) SIG_NAME M_G_MA<4>
J 0
(-1315 3585);
DISPLAY 0.659574 (-1315 3585);
PAINT MONO (-1315 3585);
DISPLAY INVISIBLE (-1315 3585);
FORCEPROP 1 LASTPIN (-1325 3575) BN 4
J 0
(-1375 3585);
DISPLAY 0.617021 (-1375 3585);
PAINT PINK (-1375 3585);
FORCEPROP 2 LAST CDS_LIB mstr_standard
J 2
(-1375 3575);
DISPLAY 0.787234 (-1375 3575);
PAINT MONO (-1375 3575);
DISPLAY INVISIBLE (-1375 3575);
FORCEPROP 1 LAST BODY_TYPE PLUMBING
J 0
(-1375 3525);
DISPLAY 1.234043 (-1375 3525);
PAINT GREEN (-1375 3525);
DISPLAY INVISIBLE (-1375 3525);
FORCEPROP 1 LAST HDL_TAP TRUE
J 0
(-1050 3450);
DISPLAY 1.234043 (-1050 3450);
PAINT GREEN (-1050 3450);
DISPLAY INVISIBLE (-1050 3450);
FORCEPROP 1 LAST PATH I51
J 0
(-1377 3575);
DISPLAY 0.872340 (-1377 3575);
PAINT GREEN (-1377 3575);
DISPLAY INVISIBLE (-1377 3575);
FORCEADD TAP..6
(-1375 3525);
FORCEPROP 3 LASTPIN (-1325 3525) SIG_NAME M_G_MA<3>
J 0
(-1315 3535);
DISPLAY 0.659574 (-1315 3535);
PAINT MONO (-1315 3535);
DISPLAY INVISIBLE (-1315 3535);
FORCEPROP 1 LASTPIN (-1325 3525) BN 3
J 0
(-1375 3535);
DISPLAY 0.617021 (-1375 3535);
PAINT PINK (-1375 3535);
FORCEPROP 2 LAST CDS_LIB mstr_standard
J 2
(-1375 3525);
DISPLAY 0.787234 (-1375 3525);
PAINT MONO (-1375 3525);
DISPLAY INVISIBLE (-1375 3525);
FORCEPROP 1 LAST BODY_TYPE PLUMBING
J 0
(-1375 3475);
DISPLAY 1.234043 (-1375 3475);
PAINT GREEN (-1375 3475);
DISPLAY INVISIBLE (-1375 3475);
FORCEPROP 1 LAST HDL_TAP TRUE
J 0
(-1050 3400);
DISPLAY 1.234043 (-1050 3400);
PAINT GREEN (-1050 3400);
DISPLAY INVISIBLE (-1050 3400);
FORCEPROP 1 LAST PATH I52
J 0
(-1377 3525);
DISPLAY 0.872340 (-1377 3525);
PAINT GREEN (-1377 3525);
DISPLAY INVISIBLE (-1377 3525);
FORCEADD TAP..6
(-1375 3625);
FORCEPROP 3 LASTPIN (-1325 3625) SIG_NAME M_G_MA<5>
J 0
(-1315 3635);
DISPLAY 0.659574 (-1315 3635);
PAINT MONO (-1315 3635);
DISPLAY INVISIBLE (-1315 3635);
FORCEPROP 1 LASTPIN (-1325 3625) BN 5
J 0
(-1375 3635);
DISPLAY 0.617021 (-1375 3635);
PAINT PINK (-1375 3635);
FORCEPROP 2 LAST CDS_LIB mstr_standard
J 2
(-1375 3625);
DISPLAY 0.787234 (-1375 3625);
PAINT MONO (-1375 3625);
DISPLAY INVISIBLE (-1375 3625);
FORCEPROP 1 LAST BODY_TYPE PLUMBING
J 0
(-1375 3575);
DISPLAY 1.234043 (-1375 3575);
PAINT GREEN (-1375 3575);
DISPLAY INVISIBLE (-1375 3575);
FORCEPROP 1 LAST HDL_TAP TRUE
J 0
(-1050 3500);
DISPLAY 1.234043 (-1050 3500);
PAINT GREEN (-1050 3500);
DISPLAY INVISIBLE (-1050 3500);
FORCEPROP 1 LAST PATH I53
J 0
(-1377 3625);
DISPLAY 0.872340 (-1377 3625);
PAINT GREEN (-1377 3625);
DISPLAY INVISIBLE (-1377 3625);
FORCEADD TAP..6
(-1375 3675);
FORCEPROP 3 LASTPIN (-1325 3675) SIG_NAME M_G_MA<6>
J 0
(-1315 3685);
DISPLAY 0.659574 (-1315 3685);
PAINT MONO (-1315 3685);
DISPLAY INVISIBLE (-1315 3685);
FORCEPROP 1 LASTPIN (-1325 3675) BN 6
J 0
(-1375 3685);
DISPLAY 0.617021 (-1375 3685);
PAINT PINK (-1375 3685);
FORCEPROP 2 LAST CDS_LIB mstr_standard
J 2
(-1375 3675);
DISPLAY 0.787234 (-1375 3675);
PAINT MONO (-1375 3675);
DISPLAY INVISIBLE (-1375 3675);
FORCEPROP 1 LAST BODY_TYPE PLUMBING
J 0
(-1375 3625);
DISPLAY 1.234043 (-1375 3625);
PAINT GREEN (-1375 3625);
DISPLAY INVISIBLE (-1375 3625);
FORCEPROP 1 LAST HDL_TAP TRUE
J 0
(-1050 3550);
DISPLAY 1.234043 (-1050 3550);
PAINT GREEN (-1050 3550);
DISPLAY INVISIBLE (-1050 3550);
FORCEPROP 1 LAST PATH I54
J 0
(-1377 3675);
DISPLAY 0.872340 (-1377 3675);
PAINT GREEN (-1377 3675);
DISPLAY INVISIBLE (-1377 3675);
FORCEADD TAP..6
(-1375 3725);
FORCEPROP 3 LASTPIN (-1325 3725) SIG_NAME M_G_MA<7>
J 0
(-1315 3735);
DISPLAY 0.659574 (-1315 3735);
PAINT MONO (-1315 3735);
DISPLAY INVISIBLE (-1315 3735);
FORCEPROP 1 LASTPIN (-1325 3725) BN 7
J 0
(-1375 3735);
DISPLAY 0.617021 (-1375 3735);
PAINT PINK (-1375 3735);
FORCEPROP 2 LAST CDS_LIB mstr_standard
J 2
(-1375 3725);
DISPLAY 0.787234 (-1375 3725);
PAINT MONO (-1375 3725);
DISPLAY INVISIBLE (-1375 3725);
FORCEPROP 1 LAST BODY_TYPE PLUMBING
J 0
(-1375 3675);
DISPLAY 1.234043 (-1375 3675);
PAINT GREEN (-1375 3675);
DISPLAY INVISIBLE (-1375 3675);
FORCEPROP 1 LAST HDL_TAP TRUE
J 0
(-1050 3600);
DISPLAY 1.234043 (-1050 3600);
PAINT GREEN (-1050 3600);
DISPLAY INVISIBLE (-1050 3600);
FORCEPROP 1 LAST PATH I55
J 0
(-1377 3725);
DISPLAY 0.872340 (-1377 3725);
PAINT GREEN (-1377 3725);
DISPLAY INVISIBLE (-1377 3725);
FORCEADD TAP..6
(-1375 3825);
FORCEPROP 3 LASTPIN (-1325 3825) SIG_NAME M_G_MA<9>
J 0
(-1315 3835);
DISPLAY 0.659574 (-1315 3835);
PAINT MONO (-1315 3835);
DISPLAY INVISIBLE (-1315 3835);
FORCEPROP 1 LASTPIN (-1325 3825) BN 9
J 0
(-1375 3835);
DISPLAY 0.617021 (-1375 3835);
PAINT PINK (-1375 3835);
FORCEPROP 2 LAST CDS_LIB mstr_standard
J 2
(-1375 3825);
DISPLAY 0.787234 (-1375 3825);
PAINT MONO (-1375 3825);
DISPLAY INVISIBLE (-1375 3825);
FORCEPROP 1 LAST BODY_TYPE PLUMBING
J 0
(-1375 3775);
DISPLAY 1.234043 (-1375 3775);
PAINT GREEN (-1375 3775);
DISPLAY INVISIBLE (-1375 3775);
FORCEPROP 1 LAST HDL_TAP TRUE
J 0
(-1050 3700);
DISPLAY 1.234043 (-1050 3700);
PAINT GREEN (-1050 3700);
DISPLAY INVISIBLE (-1050 3700);
FORCEPROP 1 LAST PATH I56
J 0
(-1377 3825);
DISPLAY 0.872340 (-1377 3825);
PAINT GREEN (-1377 3825);
DISPLAY INVISIBLE (-1377 3825);
FORCEADD TAP..6
(-1375 3775);
FORCEPROP 3 LASTPIN (-1325 3775) SIG_NAME M_G_MA<8>
J 0
(-1315 3785);
DISPLAY 0.659574 (-1315 3785);
PAINT MONO (-1315 3785);
DISPLAY INVISIBLE (-1315 3785);
FORCEPROP 1 LASTPIN (-1325 3775) BN 8
J 0
(-1375 3785);
DISPLAY 0.617021 (-1375 3785);
PAINT PINK (-1375 3785);
FORCEPROP 2 LAST CDS_LIB mstr_standard
J 2
(-1375 3775);
DISPLAY 0.787234 (-1375 3775);
PAINT MONO (-1375 3775);
DISPLAY INVISIBLE (-1375 3775);
FORCEPROP 1 LAST BODY_TYPE PLUMBING
J 0
(-1375 3725);
DISPLAY 1.234043 (-1375 3725);
PAINT GREEN (-1375 3725);
DISPLAY INVISIBLE (-1375 3725);
FORCEPROP 1 LAST HDL_TAP TRUE
J 0
(-1050 3650);
DISPLAY 1.234043 (-1050 3650);
PAINT GREEN (-1050 3650);
DISPLAY INVISIBLE (-1050 3650);
FORCEPROP 1 LAST PATH I57
J 0
(-1377 3775);
DISPLAY 0.872340 (-1377 3775);
PAINT GREEN (-1377 3775);
DISPLAY INVISIBLE (-1377 3775);
FORCEADD TAP..6
(-1375 3875);
FORCEPROP 3 LASTPIN (-1325 3875) SIG_NAME M_G_MA<10>
J 0
(-1315 3885);
DISPLAY 0.659574 (-1315 3885);
PAINT MONO (-1315 3885);
DISPLAY INVISIBLE (-1315 3885);
FORCEPROP 1 LASTPIN (-1325 3875) BN 10
J 0
(-1375 3885);
DISPLAY 0.617021 (-1375 3885);
PAINT PINK (-1375 3885);
FORCEPROP 2 LAST CDS_LIB mstr_standard
J 2
(-1375 3875);
DISPLAY 0.787234 (-1375 3875);
PAINT MONO (-1375 3875);
DISPLAY INVISIBLE (-1375 3875);
FORCEPROP 1 LAST BODY_TYPE PLUMBING
J 0
(-1375 3825);
DISPLAY 1.234043 (-1375 3825);
PAINT GREEN (-1375 3825);
DISPLAY INVISIBLE (-1375 3825);
FORCEPROP 1 LAST HDL_TAP TRUE
J 0
(-1050 3750);
DISPLAY 1.234043 (-1050 3750);
PAINT GREEN (-1050 3750);
DISPLAY INVISIBLE (-1050 3750);
FORCEPROP 1 LAST PATH I58
J 0
(-1377 3875);
DISPLAY 0.872340 (-1377 3875);
PAINT GREEN (-1377 3875);
DISPLAY INVISIBLE (-1377 3875);
FORCEADD TAP..6
R 2
(125 1075);
FORCEPROP 3 LASTPIN (75 1075) SIG_NAME M_G_DQ<0>
J 0
(85 1085);
DISPLAY 0.659574 (85 1085);
PAINT MONO (85 1085);
DISPLAY INVISIBLE (85 1085);
FORCEPROP 1 LASTPIN (75 1075) BN 0
J 2
(125 1085);
DISPLAY 0.617021 (125 1085);
PAINT PINK (125 1085);
FORCEPROP 2 LAST CDS_LIB mstr_standard
J 2
(125 1075);
DISPLAY 0.787234 (125 1075);
PAINT MONO (125 1075);
DISPLAY INVISIBLE (125 1075);
FORCEPROP 1 LAST BODY_TYPE PLUMBING
J 2
(125 1025);
DISPLAY 1.234043 (125 1025);
PAINT GREEN (125 1025);
DISPLAY INVISIBLE (125 1025);
FORCEPROP 1 LAST HDL_TAP TRUE
J 2
(-200 950);
DISPLAY 1.234043 (-200 950);
PAINT GREEN (-200 950);
DISPLAY INVISIBLE (-200 950);
FORCEPROP 1 LAST PATH I59
J 2
(127 1075);
DISPLAY 0.872340 (127 1075);
PAINT GREEN (127 1075);
DISPLAY INVISIBLE (127 1075);
FORCEADD OFFPAGE..5
(-2350 1875);
FORCEPROP 2 LAST $XR23 94 
J 0
(-2844 1911);
DISPLAY 0.638298 (-2844 1911);
PAINT MONO (-2844 1911);
FORCEPROP 2 LAST $XR22 88 
J 0
(-2754 1911);
DISPLAY 0.638298 (-2754 1911);
PAINT MONO (-2754 1911);
FORCEPROP 2 LAST $XR21 87 
J 0
(-2664 1911);
DISPLAY 0.638298 (-2664 1911);
PAINT MONO (-2664 1911);
FORCEPROP 2 LAST $XR20 86 
J 0
(-2574 1911);
DISPLAY 0.638298 (-2574 1911);
PAINT MONO (-2574 1911);
FORCEPROP 2 LAST $XR19 85 
J 0
(-3384 1839);
DISPLAY 0.638298 (-3384 1839);
PAINT MONO (-3384 1839);
FORCEPROP 2 LAST $XR18 84 
J 0
(-3294 1839);
DISPLAY 0.638298 (-3294 1839);
PAINT MONO (-3294 1839);
FORCEPROP 2 LAST $XR17 83 
J 0
(-3204 1839);
DISPLAY 0.638298 (-3204 1839);
PAINT MONO (-3204 1839);
FORCEPROP 2 LAST $XR16 82 
J 0
(-3114 1839);
DISPLAY 0.638298 (-3114 1839);
PAINT MONO (-3114 1839);
FORCEPROP 2 LAST $XR15 81 
J 0
(-3024 1839);
DISPLAY 0.638298 (-3024 1839);
PAINT MONO (-3024 1839);
FORCEPROP 2 LAST $XR14 80 
J 0
(-2934 1839);
DISPLAY 0.638298 (-2934 1839);
PAINT MONO (-2934 1839);
FORCEPROP 2 LAST $XR13 79 
J 0
(-2844 1839);
DISPLAY 0.638298 (-2844 1839);
PAINT MONO (-2844 1839);
FORCEPROP 2 LAST $XR12 77 
J 0
(-2754 1839);
DISPLAY 0.638298 (-2754 1839);
PAINT MONO (-2754 1839);
FORCEPROP 2 LAST $XR11 54 
J 0
(-2664 1839);
DISPLAY 0.638298 (-2664 1839);
PAINT MONO (-2664 1839);
FORCEPROP 2 LAST $XR10 53 
J 0
(-2574 1839);
DISPLAY 0.638298 (-2574 1839);
PAINT MONO (-2574 1839);
FORCEPROP 2 LAST $XR9 52 
J 0
(-3384 1875);
DISPLAY 0.638298 (-3384 1875);
PAINT MONO (-3384 1875);
FORCEPROP 2 LAST $XR8 51 
J 0
(-3294 1875);
DISPLAY 0.638298 (-3294 1875);
PAINT MONO (-3294 1875);
FORCEPROP 2 LAST $XR7 50 
J 0
(-3204 1875);
DISPLAY 0.638298 (-3204 1875);
PAINT MONO (-3204 1875);
FORCEPROP 2 LAST $XR6 49 
J 0
(-3114 1875);
DISPLAY 0.638298 (-3114 1875);
PAINT MONO (-3114 1875);
FORCEPROP 2 LAST $XR5 48 
J 0
(-3024 1875);
DISPLAY 0.638298 (-3024 1875);
PAINT MONO (-3024 1875);
FORCEPROP 2 LAST $XR4 47 
J 0
(-2934 1875);
DISPLAY 0.638298 (-2934 1875);
PAINT MONO (-2934 1875);
FORCEPROP 2 LAST $XR3 46 
J 0
(-2844 1875);
DISPLAY 0.638298 (-2844 1875);
PAINT MONO (-2844 1875);
FORCEPROP 2 LAST $XR2 45 
J 0
(-2754 1875);
DISPLAY 0.638298 (-2754 1875);
PAINT MONO (-2754 1875);
FORCEPROP 2 LAST $XR1 44 
J 0
(-2664 1875);
DISPLAY 0.638298 (-2664 1875);
PAINT MONO (-2664 1875);
FORCEPROP 2 LAST $XR0 43 
J 0
(-2574 1875);
DISPLAY 0.638298 (-2574 1875);
PAINT MONO (-2574 1875);
FORCEPROP 2 LAST CDS_LIB mstr_standard
J 0
(-2350 1875);
DISPLAY 0.787234 (-2350 1875);
PAINT MONO (-2350 1875);
DISPLAY INVISIBLE (-2350 1875);
FORCEPROP 1 LAST OFFPAGE TRUE
J 0
(-2025 1750);
DISPLAY 1.404255 (-2025 1750);
PAINT GREEN (-2025 1750);
DISPLAY INVISIBLE (-2025 1750);
FORCEPROP 1 LAST COMMENT_BODY TRUE
J 0
(-2250 1800);
DISPLAY 1.404255 (-2250 1800);
PAINT GREEN (-2250 1800);
DISPLAY INVISIBLE (-2250 1800);
FORCEPROP 2 LAST PATH I6
J 0
(-2550 1925);
DISPLAY 1.021277 (-2550 1925);
PAINT ORANGE (-2550 1925);
DISPLAY INVISIBLE (-2550 1925);
FORCEADD TAP..6
R 2
(125 1125);
FORCEPROP 3 LASTPIN (75 1125) SIG_NAME M_G_DQ<1>
J 0
(85 1135);
DISPLAY 0.659574 (85 1135);
PAINT MONO (85 1135);
DISPLAY INVISIBLE (85 1135);
FORCEPROP 1 LASTPIN (75 1125) BN 1
J 2
(125 1135);
DISPLAY 0.617021 (125 1135);
PAINT PINK (125 1135);
FORCEPROP 2 LAST CDS_LIB mstr_standard
J 2
(125 1125);
DISPLAY 0.787234 (125 1125);
PAINT MONO (125 1125);
DISPLAY INVISIBLE (125 1125);
FORCEPROP 1 LAST BODY_TYPE PLUMBING
J 2
(125 1075);
DISPLAY 1.234043 (125 1075);
PAINT GREEN (125 1075);
DISPLAY INVISIBLE (125 1075);
FORCEPROP 1 LAST HDL_TAP TRUE
J 2
(-200 1000);
DISPLAY 1.234043 (-200 1000);
PAINT GREEN (-200 1000);
DISPLAY INVISIBLE (-200 1000);
FORCEPROP 1 LAST PATH I60
J 2
(127 1125);
DISPLAY 0.872340 (127 1125);
PAINT GREEN (127 1125);
DISPLAY INVISIBLE (127 1125);
FORCEADD TAP..6
R 2
(125 1175);
FORCEPROP 3 LASTPIN (75 1175) SIG_NAME M_G_DQ<2>
J 0
(85 1185);
DISPLAY 0.659574 (85 1185);
PAINT MONO (85 1185);
DISPLAY INVISIBLE (85 1185);
FORCEPROP 1 LASTPIN (75 1175) BN 2
J 2
(125 1185);
DISPLAY 0.617021 (125 1185);
PAINT PINK (125 1185);
FORCEPROP 2 LAST CDS_LIB mstr_standard
J 2
(125 1175);
DISPLAY 0.787234 (125 1175);
PAINT MONO (125 1175);
DISPLAY INVISIBLE (125 1175);
FORCEPROP 1 LAST BODY_TYPE PLUMBING
J 2
(125 1125);
DISPLAY 1.234043 (125 1125);
PAINT GREEN (125 1125);
DISPLAY INVISIBLE (125 1125);
FORCEPROP 1 LAST HDL_TAP TRUE
J 2
(-200 1050);
DISPLAY 1.234043 (-200 1050);
PAINT GREEN (-200 1050);
DISPLAY INVISIBLE (-200 1050);
FORCEPROP 1 LAST PATH I61
J 2
(127 1175);
DISPLAY 0.872340 (127 1175);
PAINT GREEN (127 1175);
DISPLAY INVISIBLE (127 1175);
FORCEADD TAP..6
R 2
(125 1325);
FORCEPROP 3 LASTPIN (75 1325) SIG_NAME M_G_DQ<5>
J 0
(85 1335);
DISPLAY 0.659574 (85 1335);
PAINT MONO (85 1335);
DISPLAY INVISIBLE (85 1335);
FORCEPROP 1 LASTPIN (75 1325) BN 5
J 2
(125 1335);
DISPLAY 0.617021 (125 1335);
PAINT PINK (125 1335);
FORCEPROP 2 LAST CDS_LIB mstr_standard
J 2
(125 1325);
DISPLAY 0.787234 (125 1325);
PAINT MONO (125 1325);
DISPLAY INVISIBLE (125 1325);
FORCEPROP 1 LAST BODY_TYPE PLUMBING
J 2
(125 1275);
DISPLAY 1.234043 (125 1275);
PAINT GREEN (125 1275);
DISPLAY INVISIBLE (125 1275);
FORCEPROP 1 LAST HDL_TAP TRUE
J 2
(-200 1200);
DISPLAY 1.234043 (-200 1200);
PAINT GREEN (-200 1200);
DISPLAY INVISIBLE (-200 1200);
FORCEPROP 1 LAST PATH I62
J 2
(127 1325);
DISPLAY 0.872340 (127 1325);
PAINT GREEN (127 1325);
DISPLAY INVISIBLE (127 1325);
FORCEADD TAP..6
R 2
(125 1275);
FORCEPROP 3 LASTPIN (75 1275) SIG_NAME M_G_DQ<4>
J 0
(85 1285);
DISPLAY 0.659574 (85 1285);
PAINT MONO (85 1285);
DISPLAY INVISIBLE (85 1285);
FORCEPROP 1 LASTPIN (75 1275) BN 4
J 2
(125 1285);
DISPLAY 0.617021 (125 1285);
PAINT PINK (125 1285);
FORCEPROP 2 LAST CDS_LIB mstr_standard
J 2
(125 1275);
DISPLAY 0.787234 (125 1275);
PAINT MONO (125 1275);
DISPLAY INVISIBLE (125 1275);
FORCEPROP 1 LAST BODY_TYPE PLUMBING
J 2
(125 1225);
DISPLAY 1.234043 (125 1225);
PAINT GREEN (125 1225);
DISPLAY INVISIBLE (125 1225);
FORCEPROP 1 LAST HDL_TAP TRUE
J 2
(-200 1150);
DISPLAY 1.234043 (-200 1150);
PAINT GREEN (-200 1150);
DISPLAY INVISIBLE (-200 1150);
FORCEPROP 1 LAST PATH I63
J 2
(127 1275);
DISPLAY 0.872340 (127 1275);
PAINT GREEN (127 1275);
DISPLAY INVISIBLE (127 1275);
FORCEADD TAP..6
R 2
(125 1225);
FORCEPROP 3 LASTPIN (75 1225) SIG_NAME M_G_DQ<3>
J 0
(85 1235);
DISPLAY 0.659574 (85 1235);
PAINT MONO (85 1235);
DISPLAY INVISIBLE (85 1235);
FORCEPROP 1 LASTPIN (75 1225) BN 3
J 2
(125 1235);
DISPLAY 0.617021 (125 1235);
PAINT PINK (125 1235);
FORCEPROP 2 LAST CDS_LIB mstr_standard
J 2
(125 1225);
DISPLAY 0.787234 (125 1225);
PAINT MONO (125 1225);
DISPLAY INVISIBLE (125 1225);
FORCEPROP 1 LAST BODY_TYPE PLUMBING
J 2
(125 1175);
DISPLAY 1.234043 (125 1175);
PAINT GREEN (125 1175);
DISPLAY INVISIBLE (125 1175);
FORCEPROP 1 LAST HDL_TAP TRUE
J 2
(-200 1100);
DISPLAY 1.234043 (-200 1100);
PAINT GREEN (-200 1100);
DISPLAY INVISIBLE (-200 1100);
FORCEPROP 1 LAST PATH I64
J 2
(127 1225);
DISPLAY 0.872340 (127 1225);
PAINT GREEN (127 1225);
DISPLAY INVISIBLE (127 1225);
FORCEADD TAP..6
R 2
(125 1375);
FORCEPROP 3 LASTPIN (75 1375) SIG_NAME M_G_DQ<6>
J 0
(85 1385);
DISPLAY 0.659574 (85 1385);
PAINT MONO (85 1385);
DISPLAY INVISIBLE (85 1385);
FORCEPROP 1 LASTPIN (75 1375) BN 6
J 2
(125 1385);
DISPLAY 0.617021 (125 1385);
PAINT PINK (125 1385);
FORCEPROP 2 LAST CDS_LIB mstr_standard
J 2
(125 1375);
DISPLAY 0.787234 (125 1375);
PAINT MONO (125 1375);
DISPLAY INVISIBLE (125 1375);
FORCEPROP 1 LAST BODY_TYPE PLUMBING
J 2
(125 1325);
DISPLAY 1.234043 (125 1325);
PAINT GREEN (125 1325);
DISPLAY INVISIBLE (125 1325);
FORCEPROP 1 LAST HDL_TAP TRUE
J 2
(-200 1250);
DISPLAY 1.234043 (-200 1250);
PAINT GREEN (-200 1250);
DISPLAY INVISIBLE (-200 1250);
FORCEPROP 1 LAST PATH I65
J 2
(127 1375);
DISPLAY 0.872340 (127 1375);
PAINT GREEN (127 1375);
DISPLAY INVISIBLE (127 1375);
FORCEADD TAP..6
R 2
(125 1425);
FORCEPROP 3 LASTPIN (75 1425) SIG_NAME M_G_DQ<7>
J 0
(85 1435);
DISPLAY 0.659574 (85 1435);
PAINT MONO (85 1435);
DISPLAY INVISIBLE (85 1435);
FORCEPROP 1 LASTPIN (75 1425) BN 7
J 2
(125 1435);
DISPLAY 0.617021 (125 1435);
PAINT PINK (125 1435);
FORCEPROP 2 LAST CDS_LIB mstr_standard
J 2
(125 1425);
DISPLAY 0.787234 (125 1425);
PAINT MONO (125 1425);
DISPLAY INVISIBLE (125 1425);
FORCEPROP 1 LAST BODY_TYPE PLUMBING
J 2
(125 1375);
DISPLAY 1.234043 (125 1375);
PAINT GREEN (125 1375);
DISPLAY INVISIBLE (125 1375);
FORCEPROP 1 LAST HDL_TAP TRUE
J 2
(-200 1300);
DISPLAY 1.234043 (-200 1300);
PAINT GREEN (-200 1300);
DISPLAY INVISIBLE (-200 1300);
FORCEPROP 1 LAST PATH I66
J 2
(127 1425);
DISPLAY 0.872340 (127 1425);
PAINT GREEN (127 1425);
DISPLAY INVISIBLE (127 1425);
FORCEADD TAP..6
R 2
(125 1475);
FORCEPROP 3 LASTPIN (75 1475) SIG_NAME M_G_DQ<8>
J 0
(85 1485);
DISPLAY 0.659574 (85 1485);
PAINT MONO (85 1485);
DISPLAY INVISIBLE (85 1485);
FORCEPROP 1 LASTPIN (75 1475) BN 8
J 2
(125 1485);
DISPLAY 0.617021 (125 1485);
PAINT PINK (125 1485);
FORCEPROP 2 LAST CDS_LIB mstr_standard
J 2
(125 1475);
DISPLAY 0.787234 (125 1475);
PAINT MONO (125 1475);
DISPLAY INVISIBLE (125 1475);
FORCEPROP 1 LAST BODY_TYPE PLUMBING
J 2
(125 1425);
DISPLAY 1.234043 (125 1425);
PAINT GREEN (125 1425);
DISPLAY INVISIBLE (125 1425);
FORCEPROP 1 LAST HDL_TAP TRUE
J 2
(-200 1350);
DISPLAY 1.234043 (-200 1350);
PAINT GREEN (-200 1350);
DISPLAY INVISIBLE (-200 1350);
FORCEPROP 1 LAST PATH I67
J 2
(127 1475);
DISPLAY 0.872340 (127 1475);
PAINT GREEN (127 1475);
DISPLAY INVISIBLE (127 1475);
FORCEADD TAP..6
R 2
(125 1525);
FORCEPROP 3 LASTPIN (75 1525) SIG_NAME M_G_DQ<9>
J 0
(85 1535);
DISPLAY 0.659574 (85 1535);
PAINT MONO (85 1535);
DISPLAY INVISIBLE (85 1535);
FORCEPROP 1 LASTPIN (75 1525) BN 9
J 2
(125 1535);
DISPLAY 0.617021 (125 1535);
PAINT PINK (125 1535);
FORCEPROP 2 LAST CDS_LIB mstr_standard
J 2
(125 1525);
DISPLAY 0.787234 (125 1525);
PAINT MONO (125 1525);
DISPLAY INVISIBLE (125 1525);
FORCEPROP 1 LAST BODY_TYPE PLUMBING
J 2
(125 1475);
DISPLAY 1.234043 (125 1475);
PAINT GREEN (125 1475);
DISPLAY INVISIBLE (125 1475);
FORCEPROP 1 LAST HDL_TAP TRUE
J 2
(-200 1400);
DISPLAY 1.234043 (-200 1400);
PAINT GREEN (-200 1400);
DISPLAY INVISIBLE (-200 1400);
FORCEPROP 1 LAST PATH I68
J 2
(127 1525);
DISPLAY 0.872340 (127 1525);
PAINT GREEN (127 1525);
DISPLAY INVISIBLE (127 1525);
FORCEADD TAP..6
R 2
(125 1575);
FORCEPROP 3 LASTPIN (75 1575) SIG_NAME M_G_DQ<10>
J 0
(85 1585);
DISPLAY 0.659574 (85 1585);
PAINT MONO (85 1585);
DISPLAY INVISIBLE (85 1585);
FORCEPROP 1 LASTPIN (75 1575) BN 10
J 2
(125 1585);
DISPLAY 0.617021 (125 1585);
PAINT PINK (125 1585);
FORCEPROP 2 LAST CDS_LIB mstr_standard
J 2
(125 1575);
DISPLAY 0.787234 (125 1575);
PAINT MONO (125 1575);
DISPLAY INVISIBLE (125 1575);
FORCEPROP 1 LAST BODY_TYPE PLUMBING
J 2
(125 1525);
DISPLAY 1.234043 (125 1525);
PAINT GREEN (125 1525);
DISPLAY INVISIBLE (125 1525);
FORCEPROP 1 LAST HDL_TAP TRUE
J 2
(-200 1450);
DISPLAY 1.234043 (-200 1450);
PAINT GREEN (-200 1450);
DISPLAY INVISIBLE (-200 1450);
FORCEPROP 1 LAST PATH I69
J 2
(127 1575);
DISPLAY 0.872340 (127 1575);
PAINT GREEN (127 1575);
DISPLAY INVISIBLE (127 1575);
FORCEADD OFFPAGE..5
(-2200 1575);
FORCEPROP 2 LAST $XR1 57 
J 0
(-2544 1575);
DISPLAY 0.638298 (-2544 1575);
PAINT MONO (-2544 1575);
FORCEPROP 2 LAST $XR0 77 
J 0
(-2454 1575);
DISPLAY 0.638298 (-2454 1575);
PAINT MONO (-2454 1575);
FORCEPROP 2 LAST CDS_LIB mstr_standard
J 0
(-2200 1575);
DISPLAY 0.787234 (-2200 1575);
PAINT MONO (-2200 1575);
DISPLAY INVISIBLE (-2200 1575);
FORCEPROP 1 LAST OFFPAGE TRUE
J 0
(-1875 1450);
DISPLAY 1.404255 (-1875 1450);
PAINT GREEN (-1875 1450);
DISPLAY INVISIBLE (-1875 1450);
FORCEPROP 1 LAST COMMENT_BODY TRUE
J 0
(-2100 1500);
DISPLAY 1.404255 (-2100 1500);
PAINT GREEN (-2100 1500);
DISPLAY INVISIBLE (-2100 1500);
FORCEPROP 2 LAST PATH I7
J 0
(-2450 1625);
DISPLAY 1.021277 (-2450 1625);
PAINT ORANGE (-2450 1625);
DISPLAY INVISIBLE (-2450 1625);
FORCEADD TAP..6
R 2
(125 1725);
FORCEPROP 3 LASTPIN (75 1725) SIG_NAME M_G_DQ<13>
J 0
(85 1735);
DISPLAY 0.659574 (85 1735);
PAINT MONO (85 1735);
DISPLAY INVISIBLE (85 1735);
FORCEPROP 1 LASTPIN (75 1725) BN 13
J 2
(125 1735);
DISPLAY 0.617021 (125 1735);
PAINT PINK (125 1735);
FORCEPROP 2 LAST CDS_LIB mstr_standard
J 2
(125 1725);
DISPLAY 0.787234 (125 1725);
PAINT MONO (125 1725);
DISPLAY INVISIBLE (125 1725);
FORCEPROP 1 LAST BODY_TYPE PLUMBING
J 2
(125 1675);
DISPLAY 1.234043 (125 1675);
PAINT GREEN (125 1675);
DISPLAY INVISIBLE (125 1675);
FORCEPROP 1 LAST HDL_TAP TRUE
J 2
(-200 1600);
DISPLAY 1.234043 (-200 1600);
PAINT GREEN (-200 1600);
DISPLAY INVISIBLE (-200 1600);
FORCEPROP 1 LAST PATH I70
J 2
(127 1725);
DISPLAY 0.872340 (127 1725);
PAINT GREEN (127 1725);
DISPLAY INVISIBLE (127 1725);
FORCEADD TAP..6
R 2
(125 1625);
FORCEPROP 3 LASTPIN (75 1625) SIG_NAME M_G_DQ<11>
J 0
(85 1635);
DISPLAY 0.659574 (85 1635);
PAINT MONO (85 1635);
DISPLAY INVISIBLE (85 1635);
FORCEPROP 1 LASTPIN (75 1625) BN 11
J 2
(125 1635);
DISPLAY 0.617021 (125 1635);
PAINT PINK (125 1635);
FORCEPROP 2 LAST CDS_LIB mstr_standard
J 2
(125 1625);
DISPLAY 0.787234 (125 1625);
PAINT MONO (125 1625);
DISPLAY INVISIBLE (125 1625);
FORCEPROP 1 LAST BODY_TYPE PLUMBING
J 2
(125 1575);
DISPLAY 1.234043 (125 1575);
PAINT GREEN (125 1575);
DISPLAY INVISIBLE (125 1575);
FORCEPROP 1 LAST HDL_TAP TRUE
J 2
(-200 1500);
DISPLAY 1.234043 (-200 1500);
PAINT GREEN (-200 1500);
DISPLAY INVISIBLE (-200 1500);
FORCEPROP 1 LAST PATH I71
J 2
(127 1625);
DISPLAY 0.872340 (127 1625);
PAINT GREEN (127 1625);
DISPLAY INVISIBLE (127 1625);
FORCEADD TAP..6
R 2
(125 1675);
FORCEPROP 3 LASTPIN (75 1675) SIG_NAME M_G_DQ<12>
J 0
(85 1685);
DISPLAY 0.659574 (85 1685);
PAINT MONO (85 1685);
DISPLAY INVISIBLE (85 1685);
FORCEPROP 1 LASTPIN (75 1675) BN 12
J 2
(125 1685);
DISPLAY 0.617021 (125 1685);
PAINT PINK (125 1685);
FORCEPROP 2 LAST CDS_LIB mstr_standard
J 2
(125 1675);
DISPLAY 0.787234 (125 1675);
PAINT MONO (125 1675);
DISPLAY INVISIBLE (125 1675);
FORCEPROP 1 LAST BODY_TYPE PLUMBING
J 2
(125 1625);
DISPLAY 1.234043 (125 1625);
PAINT GREEN (125 1625);
DISPLAY INVISIBLE (125 1625);
FORCEPROP 1 LAST HDL_TAP TRUE
J 2
(-200 1550);
DISPLAY 1.234043 (-200 1550);
PAINT GREEN (-200 1550);
DISPLAY INVISIBLE (-200 1550);
FORCEPROP 1 LAST PATH I72
J 2
(127 1675);
DISPLAY 0.872340 (127 1675);
PAINT GREEN (127 1675);
DISPLAY INVISIBLE (127 1675);
FORCEADD TAP..6
R 2
(125 1775);
FORCEPROP 3 LASTPIN (75 1775) SIG_NAME M_G_DQ<14>
J 0
(85 1785);
DISPLAY 0.659574 (85 1785);
PAINT MONO (85 1785);
DISPLAY INVISIBLE (85 1785);
FORCEPROP 1 LASTPIN (75 1775) BN 14
J 2
(125 1785);
DISPLAY 0.617021 (125 1785);
PAINT PINK (125 1785);
FORCEPROP 2 LAST CDS_LIB mstr_standard
J 2
(125 1775);
DISPLAY 0.787234 (125 1775);
PAINT MONO (125 1775);
DISPLAY INVISIBLE (125 1775);
FORCEPROP 1 LAST BODY_TYPE PLUMBING
J 2
(125 1725);
DISPLAY 1.234043 (125 1725);
PAINT GREEN (125 1725);
DISPLAY INVISIBLE (125 1725);
FORCEPROP 1 LAST HDL_TAP TRUE
J 2
(-200 1650);
DISPLAY 1.234043 (-200 1650);
PAINT GREEN (-200 1650);
DISPLAY INVISIBLE (-200 1650);
FORCEPROP 1 LAST PATH I73
J 2
(127 1775);
DISPLAY 0.872340 (127 1775);
PAINT GREEN (127 1775);
DISPLAY INVISIBLE (127 1775);
FORCEADD TAP..6
R 2
(125 1825);
FORCEPROP 3 LASTPIN (75 1825) SIG_NAME M_G_DQ<15>
J 0
(85 1835);
DISPLAY 0.659574 (85 1835);
PAINT MONO (85 1835);
DISPLAY INVISIBLE (85 1835);
FORCEPROP 1 LASTPIN (75 1825) BN 15
J 2
(125 1835);
DISPLAY 0.617021 (125 1835);
PAINT PINK (125 1835);
FORCEPROP 2 LAST CDS_LIB mstr_standard
J 2
(125 1825);
DISPLAY 0.787234 (125 1825);
PAINT MONO (125 1825);
DISPLAY INVISIBLE (125 1825);
FORCEPROP 1 LAST BODY_TYPE PLUMBING
J 2
(125 1775);
DISPLAY 1.234043 (125 1775);
PAINT GREEN (125 1775);
DISPLAY INVISIBLE (125 1775);
FORCEPROP 1 LAST HDL_TAP TRUE
J 2
(-200 1700);
DISPLAY 1.234043 (-200 1700);
PAINT GREEN (-200 1700);
DISPLAY INVISIBLE (-200 1700);
FORCEPROP 1 LAST PATH I74
J 2
(127 1825);
DISPLAY 0.872340 (127 1825);
PAINT GREEN (127 1825);
DISPLAY INVISIBLE (127 1825);
FORCEADD SCONN288_H44441003..4
(1450 1750);
FORCEPROP 1 LAST LOCATION J9T1
J 0
(1000 2850);
DISPLAY 0.617021 (1000 2850);
PAINT AQUA (1000 2850);
FORCEPROP 1 LAST PART_NUMBER H44441-003
J 0
(1000 700);
DISPLAY 0.617021 (1000 700);
PAINT BLUE (1000 700);
FORCEPROP 1 LAST MATERIAL SCONN
J 0
(1000 2800);
DISPLAY 0.617021 (1000 2800);
PAINT SKYBLUE (1000 2800);
FORCEPROP 2 LASTPIN (950 2300) $PN 77
J 2
(940 2310);
DISPLAY 0.617021 (940 2310);
PAINT ORANGE (940 2310);
FORCEPROP 2 LASTPIN (950 2250) $PN 221
J 2
(940 2260);
DISPLAY 0.617021 (940 2260);
PAINT ORANGE (940 2260);
FORCEPROP 2 LASTPIN (950 2600) $PN 142
J 2
(940 2610);
DISPLAY 0.617021 (940 2610);
PAINT ORANGE (940 2610);
FORCEPROP 2 LASTPIN (950 2550) $PN 143
J 2
(940 2560);
DISPLAY 0.617021 (940 2560);
PAINT ORANGE (940 2560);
FORCEPROP 2 LASTPIN (950 2500) $PN 288
J 2
(940 2510);
DISPLAY 0.617021 (940 2510);
PAINT ORANGE (940 2510);
FORCEPROP 2 LASTPIN (950 2450) $PN 286
J 2
(940 2460);
DISPLAY 0.617021 (940 2460);
PAINT ORANGE (940 2460);
FORCEPROP 2 LASTPIN (950 2400) $PN 287
J 2
(940 2410);
DISPLAY 0.617021 (940 2410);
PAINT ORANGE (940 2410);
FORCEPROP 2 LASTPIN (950 2150) $PN 59
J 2
(940 2160);
DISPLAY 0.617021 (940 2160);
PAINT ORANGE (940 2160);
FORCEPROP 2 LASTPIN (950 2100) $PN 61
J 2
(940 2110);
DISPLAY 0.617021 (940 2110);
PAINT ORANGE (940 2110);
FORCEPROP 2 LASTPIN (950 2050) $PN 64
J 2
(940 2060);
DISPLAY 0.617021 (940 2060);
PAINT ORANGE (940 2060);
FORCEPROP 2 LASTPIN (950 2000) $PN 67
J 2
(940 2010);
DISPLAY 0.617021 (940 2010);
PAINT ORANGE (940 2010);
FORCEPROP 2 LASTPIN (950 1950) $PN 70
J 2
(940 1960);
DISPLAY 0.617021 (940 1960);
PAINT ORANGE (940 1960);
FORCEPROP 2 LASTPIN (950 1900) $PN 73
J 2
(940 1910);
DISPLAY 0.617021 (940 1910);
PAINT ORANGE (940 1910);
FORCEPROP 2 LASTPIN (950 1850) $PN 76
J 2
(940 1860);
DISPLAY 0.617021 (940 1860);
PAINT ORANGE (940 1860);
FORCEPROP 2 LASTPIN (950 1800) $PN 80
J 2
(940 1810);
DISPLAY 0.617021 (940 1810);
PAINT ORANGE (940 1810);
FORCEPROP 2 LASTPIN (950 1750) $PN 83
J 2
(940 1760);
DISPLAY 0.617021 (940 1760);
PAINT ORANGE (940 1760);
FORCEPROP 2 LASTPIN (950 1700) $PN 85
J 2
(940 1710);
DISPLAY 0.617021 (940 1710);
PAINT ORANGE (940 1710);
FORCEPROP 2 LASTPIN (950 1650) $PN 88
J 2
(940 1660);
DISPLAY 0.617021 (940 1660);
PAINT ORANGE (940 1660);
FORCEPROP 2 LASTPIN (950 1600) $PN 90
J 2
(940 1610);
DISPLAY 0.617021 (940 1610);
PAINT ORANGE (940 1610);
FORCEPROP 2 LASTPIN (950 1550) $PN 92
J 2
(940 1560);
DISPLAY 0.617021 (940 1560);
PAINT ORANGE (940 1560);
FORCEPROP 2 LASTPIN (950 1500) $PN 204
J 2
(940 1510);
DISPLAY 0.617021 (940 1510);
PAINT ORANGE (940 1510);
FORCEPROP 2 LASTPIN (950 1450) $PN 206
J 2
(940 1460);
DISPLAY 0.617021 (940 1460);
PAINT ORANGE (940 1460);
FORCEPROP 2 LASTPIN (950 1400) $PN 209
J 2
(940 1410);
DISPLAY 0.617021 (940 1410);
PAINT ORANGE (940 1410);
FORCEPROP 2 LASTPIN (950 1350) $PN 212
J 2
(940 1360);
DISPLAY 0.617021 (940 1360);
PAINT ORANGE (940 1360);
FORCEPROP 2 LASTPIN (950 1300) $PN 215
J 2
(940 1310);
DISPLAY 0.617021 (940 1310);
PAINT ORANGE (940 1310);
FORCEPROP 2 LASTPIN (950 1250) $PN 217
J 2
(940 1260);
DISPLAY 0.617021 (940 1260);
PAINT ORANGE (940 1260);
FORCEPROP 2 LASTPIN (950 1200) $PN 220
J 2
(940 1210);
DISPLAY 0.617021 (940 1210);
PAINT ORANGE (940 1210);
FORCEPROP 2 LASTPIN (950 1150) $PN 223
J 2
(940 1160);
DISPLAY 0.617021 (940 1160);
PAINT ORANGE (940 1160);
FORCEPROP 2 LASTPIN (950 1100) $PN 226
J 2
(940 1110);
DISPLAY 0.617021 (940 1110);
PAINT ORANGE (940 1110);
FORCEPROP 2 LASTPIN (950 1050) $PN 229
J 2
(940 1060);
DISPLAY 0.617021 (940 1060);
PAINT ORANGE (940 1060);
FORCEPROP 2 LASTPIN (950 1000) $PN 231
J 2
(940 1010);
DISPLAY 0.617021 (940 1010);
PAINT ORANGE (940 1010);
FORCEPROP 2 LASTPIN (950 950) $PN 233
J 2
(940 960);
DISPLAY 0.617021 (940 960);
PAINT ORANGE (940 960);
FORCEPROP 2 LASTPIN (950 900) $PN 236
J 2
(940 910);
DISPLAY 0.617021 (940 910);
PAINT ORANGE (940 910);
FORCEPROP 2 LASTPIN (1950 2600) $PN 1
J 0
(1960 2610);
DISPLAY 0.617021 (1960 2610);
PAINT ORANGE (1960 2610);
FORCEPROP 2 LASTPIN (1950 2550) $PN 145
J 0
(1960 2560);
DISPLAY 0.617021 (1960 2560);
PAINT ORANGE (1960 2560);
FORCEPROP 0 LAST BOM_SS NOPOP
J 0
(1277 2791);
DISPLAY 1.021277 (1277 2791);
PAINT BROWN (1277 2791);
DISPLAY BOTH (1277 2791);
FORCEPROP 1 LAST PACK_TYPE PIP
J 0
(1000 2900);
PAINT SKYBLUE (1000 2900);
DISPLAY INVISIBLE (1000 2900);
FORCEPROP 2 LAST BOM_COST MEM
J 0
(1450 1750);
PAINT ORANGE (1450 1750);
DISPLAY INVISIBLE (1450 1750);
FORCEPROP 2 LAST CDS_LIB mstr_sconn
J 0
(1450 1750);
PAINT ORANGE (1450 1750);
DISPLAY INVISIBLE (1450 1750);
FORCEPROP 2 LAST SEC_TYPE PIP
J 0
(1000 2900);
DISPLAY 1.021277 (1000 2900);
PAINT ORANGE (1000 2900);
DISPLAY INVISIBLE (1000 2900);
FORCEPROP 2 LAST SEC 4
J 0
(1000 2900);
DISPLAY 0.680851 (1000 2900);
PAINT MONO (1000 2900);
DISPLAY INVISIBLE (1000 2900);
FORCEPROP 2 LAST CDS_LOCATION J9T1
J 0
(1000 2850);
DISPLAY 0.617021 (1000 2850);
PAINT AQUA (1000 2850);
DISPLAY INVISIBLE (1000 2850);
FORCEPROP 1 LAST PATH I75
J 0
(1450 2800);
PAINT GREEN (1450 2800);
DISPLAY INVISIBLE (1450 2800);
FORCEPROP 2 LAST ROOM DDR4_GH_G
J 0
(1450 1750);
PAINT ORANGE (1450 1750);
DISPLAY INVISIBLE (1450 1750);
FORCEADD TAP..6
R 2
(125 1925);
FORCEPROP 3 LASTPIN (75 1925) SIG_NAME M_G_DQ<17>
J 0
(85 1935);
DISPLAY 0.659574 (85 1935);
PAINT MONO (85 1935);
DISPLAY INVISIBLE (85 1935);
FORCEPROP 1 LASTPIN (75 1925) BN 17
J 2
(125 1935);
DISPLAY 0.617021 (125 1935);
PAINT PINK (125 1935);
FORCEPROP 2 LAST CDS_LIB mstr_standard
J 2
(125 1925);
DISPLAY 0.787234 (125 1925);
PAINT MONO (125 1925);
DISPLAY INVISIBLE (125 1925);
FORCEPROP 1 LAST BODY_TYPE PLUMBING
J 2
(125 1875);
DISPLAY 1.234043 (125 1875);
PAINT GREEN (125 1875);
DISPLAY INVISIBLE (125 1875);
FORCEPROP 1 LAST HDL_TAP TRUE
J 2
(-200 1800);
DISPLAY 1.234043 (-200 1800);
PAINT GREEN (-200 1800);
DISPLAY INVISIBLE (-200 1800);
FORCEPROP 1 LAST PATH I76
J 2
(127 1925);
DISPLAY 0.872340 (127 1925);
PAINT GREEN (127 1925);
DISPLAY INVISIBLE (127 1925);
FORCEADD TAP..6
R 2
(125 1875);
FORCEPROP 3 LASTPIN (75 1875) SIG_NAME M_G_DQ<16>
J 0
(85 1885);
DISPLAY 0.659574 (85 1885);
PAINT MONO (85 1885);
DISPLAY INVISIBLE (85 1885);
FORCEPROP 1 LASTPIN (75 1875) BN 16
J 2
(125 1885);
DISPLAY 0.617021 (125 1885);
PAINT PINK (125 1885);
FORCEPROP 2 LAST CDS_LIB mstr_standard
J 2
(125 1875);
DISPLAY 0.787234 (125 1875);
PAINT MONO (125 1875);
DISPLAY INVISIBLE (125 1875);
FORCEPROP 1 LAST BODY_TYPE PLUMBING
J 2
(125 1825);
DISPLAY 1.234043 (125 1825);
PAINT GREEN (125 1825);
DISPLAY INVISIBLE (125 1825);
FORCEPROP 1 LAST HDL_TAP TRUE
J 2
(-200 1750);
DISPLAY 1.234043 (-200 1750);
PAINT GREEN (-200 1750);
DISPLAY INVISIBLE (-200 1750);
FORCEPROP 1 LAST PATH I77
J 2
(127 1875);
DISPLAY 0.872340 (127 1875);
PAINT GREEN (127 1875);
DISPLAY INVISIBLE (127 1875);
FORCEADD TAP..6
R 2
(125 1975);
FORCEPROP 3 LASTPIN (75 1975) SIG_NAME M_G_DQ<18>
J 0
(85 1985);
DISPLAY 0.659574 (85 1985);
PAINT MONO (85 1985);
DISPLAY INVISIBLE (85 1985);
FORCEPROP 1 LASTPIN (75 1975) BN 18
J 2
(125 1985);
DISPLAY 0.617021 (125 1985);
PAINT PINK (125 1985);
FORCEPROP 2 LAST CDS_LIB mstr_standard
J 2
(125 1975);
DISPLAY 0.787234 (125 1975);
PAINT MONO (125 1975);
DISPLAY INVISIBLE (125 1975);
FORCEPROP 1 LAST BODY_TYPE PLUMBING
J 2
(125 1925);
DISPLAY 1.234043 (125 1925);
PAINT GREEN (125 1925);
DISPLAY INVISIBLE (125 1925);
FORCEPROP 1 LAST HDL_TAP TRUE
J 2
(-200 1850);
DISPLAY 1.234043 (-200 1850);
PAINT GREEN (-200 1850);
DISPLAY INVISIBLE (-200 1850);
FORCEPROP 1 LAST PATH I78
J 2
(127 1975);
DISPLAY 0.872340 (127 1975);
PAINT GREEN (127 1975);
DISPLAY INVISIBLE (127 1975);
FORCEADD TAP..6
R 2
(125 2025);
FORCEPROP 3 LASTPIN (75 2025) SIG_NAME M_G_DQ<19>
J 0
(85 2035);
DISPLAY 0.659574 (85 2035);
PAINT MONO (85 2035);
DISPLAY INVISIBLE (85 2035);
FORCEPROP 1 LASTPIN (75 2025) BN 19
J 2
(125 2035);
DISPLAY 0.617021 (125 2035);
PAINT PINK (125 2035);
FORCEPROP 2 LAST CDS_LIB mstr_standard
J 2
(125 2025);
DISPLAY 0.787234 (125 2025);
PAINT MONO (125 2025);
DISPLAY INVISIBLE (125 2025);
FORCEPROP 1 LAST BODY_TYPE PLUMBING
J 2
(125 1975);
DISPLAY 1.234043 (125 1975);
PAINT GREEN (125 1975);
DISPLAY INVISIBLE (125 1975);
FORCEPROP 1 LAST HDL_TAP TRUE
J 2
(-200 1900);
DISPLAY 1.234043 (-200 1900);
PAINT GREEN (-200 1900);
DISPLAY INVISIBLE (-200 1900);
FORCEPROP 1 LAST PATH I79
J 2
(127 2025);
DISPLAY 0.872340 (127 2025);
PAINT GREEN (127 2025);
DISPLAY INVISIBLE (127 2025);
FORCEADD OFFPAGE..1
(-2025 775);
FORCEPROP 2 LAST $XR5 82 
J 0
(-2246 739);
DISPLAY 0.638298 (-2246 739);
PAINT MONO (-2246 739);
FORCEPROP 2 LAST $XR4 81 
J 0
(-2606 775);
DISPLAY 0.638298 (-2606 775);
PAINT MONO (-2606 775);
FORCEPROP 2 LAST $XR3 80 
J 0
(-2516 775);
DISPLAY 0.638298 (-2516 775);
PAINT MONO (-2516 775);
FORCEPROP 2 LAST $XR2 79 
J 0
(-2426 775);
DISPLAY 0.638298 (-2426 775);
PAINT MONO (-2426 775);
FORCEPROP 2 LAST $XR1 77 
J 0
(-2336 775);
DISPLAY 0.638298 (-2336 775);
PAINT MONO (-2336 775);
FORCEPROP 2 LAST $XR0 89 
J 0
(-2246 775);
DISPLAY 0.638298 (-2246 775);
PAINT MONO (-2246 775);
FORCEPROP 2 LAST CDS_LIB mstr_standard
J 0
(-2025 775);
PAINT ORANGE (-2025 775);
DISPLAY INVISIBLE (-2025 775);
FORCEPROP 1 LAST OFFPAGE TRUE
J 0
(-1700 650);
DISPLAY 0.936170 (-1700 650);
PAINT GREEN (-1700 650);
DISPLAY INVISIBLE (-1700 650);
FORCEPROP 1 LAST COMMENT_BODY TRUE
J 0
(-1900 675);
DISPLAY 0.936170 (-1900 675);
PAINT GREEN (-1900 675);
DISPLAY INVISIBLE (-1900 675);
FORCEPROP 2 LAST PATH I8
J 0
(-2275 825);
DISPLAY 1.021277 (-2275 825);
PAINT ORANGE (-2275 825);
DISPLAY INVISIBLE (-2275 825);
FORCEADD TAP..6
R 2
(125 2075);
FORCEPROP 3 LASTPIN (75 2075) SIG_NAME M_G_DQ<20>
J 0
(85 2085);
DISPLAY 0.659574 (85 2085);
PAINT MONO (85 2085);
DISPLAY INVISIBLE (85 2085);
FORCEPROP 1 LASTPIN (75 2075) BN 20
J 2
(125 2085);
DISPLAY 0.617021 (125 2085);
PAINT PINK (125 2085);
FORCEPROP 2 LAST CDS_LIB mstr_standard
J 2
(125 2075);
DISPLAY 0.787234 (125 2075);
PAINT MONO (125 2075);
DISPLAY INVISIBLE (125 2075);
FORCEPROP 1 LAST BODY_TYPE PLUMBING
J 2
(125 2025);
DISPLAY 1.234043 (125 2025);
PAINT GREEN (125 2025);
DISPLAY INVISIBLE (125 2025);
FORCEPROP 1 LAST HDL_TAP TRUE
J 2
(-200 1950);
DISPLAY 1.234043 (-200 1950);
PAINT GREEN (-200 1950);
DISPLAY INVISIBLE (-200 1950);
FORCEPROP 1 LAST PATH I80
J 2
(127 2075);
DISPLAY 0.872340 (127 2075);
PAINT GREEN (127 2075);
DISPLAY INVISIBLE (127 2075);
FORCEADD TAP..6
R 2
(125 2225);
FORCEPROP 3 LASTPIN (75 2225) SIG_NAME M_G_DQ<23>
J 0
(85 2235);
DISPLAY 0.659574 (85 2235);
PAINT MONO (85 2235);
DISPLAY INVISIBLE (85 2235);
FORCEPROP 1 LASTPIN (75 2225) BN 23
J 2
(125 2235);
DISPLAY 0.617021 (125 2235);
PAINT PINK (125 2235);
FORCEPROP 2 LAST CDS_LIB mstr_standard
J 2
(125 2225);
DISPLAY 0.787234 (125 2225);
PAINT MONO (125 2225);
DISPLAY INVISIBLE (125 2225);
FORCEPROP 1 LAST BODY_TYPE PLUMBING
J 2
(125 2175);
DISPLAY 1.234043 (125 2175);
PAINT GREEN (125 2175);
DISPLAY INVISIBLE (125 2175);
FORCEPROP 1 LAST HDL_TAP TRUE
J 2
(-200 2100);
DISPLAY 1.234043 (-200 2100);
PAINT GREEN (-200 2100);
DISPLAY INVISIBLE (-200 2100);
FORCEPROP 1 LAST PATH I81
J 2
(127 2225);
DISPLAY 0.872340 (127 2225);
PAINT GREEN (127 2225);
DISPLAY INVISIBLE (127 2225);
FORCEADD TAP..6
R 2
(125 2175);
FORCEPROP 3 LASTPIN (75 2175) SIG_NAME M_G_DQ<22>
J 0
(85 2185);
DISPLAY 0.659574 (85 2185);
PAINT MONO (85 2185);
DISPLAY INVISIBLE (85 2185);
FORCEPROP 1 LASTPIN (75 2175) BN 22
J 2
(125 2185);
DISPLAY 0.617021 (125 2185);
PAINT PINK (125 2185);
FORCEPROP 2 LAST CDS_LIB mstr_standard
J 2
(125 2175);
DISPLAY 0.787234 (125 2175);
PAINT MONO (125 2175);
DISPLAY INVISIBLE (125 2175);
FORCEPROP 1 LAST BODY_TYPE PLUMBING
J 2
(125 2125);
DISPLAY 1.234043 (125 2125);
PAINT GREEN (125 2125);
DISPLAY INVISIBLE (125 2125);
FORCEPROP 1 LAST HDL_TAP TRUE
J 2
(-200 2050);
DISPLAY 1.234043 (-200 2050);
PAINT GREEN (-200 2050);
DISPLAY INVISIBLE (-200 2050);
FORCEPROP 1 LAST PATH I82
J 2
(127 2175);
DISPLAY 0.872340 (127 2175);
PAINT GREEN (127 2175);
DISPLAY INVISIBLE (127 2175);
FORCEADD TAP..6
R 2
(125 2125);
FORCEPROP 3 LASTPIN (75 2125) SIG_NAME M_G_DQ<21>
J 0
(85 2135);
DISPLAY 0.659574 (85 2135);
PAINT MONO (85 2135);
DISPLAY INVISIBLE (85 2135);
FORCEPROP 1 LASTPIN (75 2125) BN 21
J 2
(125 2135);
DISPLAY 0.617021 (125 2135);
PAINT PINK (125 2135);
FORCEPROP 2 LAST CDS_LIB mstr_standard
J 2
(125 2125);
DISPLAY 0.787234 (125 2125);
PAINT MONO (125 2125);
DISPLAY INVISIBLE (125 2125);
FORCEPROP 1 LAST BODY_TYPE PLUMBING
J 2
(125 2075);
DISPLAY 1.234043 (125 2075);
PAINT GREEN (125 2075);
DISPLAY INVISIBLE (125 2075);
FORCEPROP 1 LAST HDL_TAP TRUE
J 2
(-200 2000);
DISPLAY 1.234043 (-200 2000);
PAINT GREEN (-200 2000);
DISPLAY INVISIBLE (-200 2000);
FORCEPROP 1 LAST PATH I83
J 2
(127 2125);
DISPLAY 0.872340 (127 2125);
PAINT GREEN (127 2125);
DISPLAY INVISIBLE (127 2125);
FORCEADD TAP..6
R 2
(125 2325);
FORCEPROP 3 LASTPIN (75 2325) SIG_NAME M_G_DQ<25>
J 0
(85 2335);
DISPLAY 0.659574 (85 2335);
PAINT MONO (85 2335);
DISPLAY INVISIBLE (85 2335);
FORCEPROP 1 LASTPIN (75 2325) BN 25
J 2
(125 2335);
DISPLAY 0.617021 (125 2335);
PAINT PINK (125 2335);
FORCEPROP 2 LAST CDS_LIB mstr_standard
J 2
(125 2325);
DISPLAY 0.787234 (125 2325);
PAINT MONO (125 2325);
DISPLAY INVISIBLE (125 2325);
FORCEPROP 1 LAST BODY_TYPE PLUMBING
J 2
(125 2275);
DISPLAY 1.234043 (125 2275);
PAINT GREEN (125 2275);
DISPLAY INVISIBLE (125 2275);
FORCEPROP 1 LAST HDL_TAP TRUE
J 2
(-200 2200);
DISPLAY 1.234043 (-200 2200);
PAINT GREEN (-200 2200);
DISPLAY INVISIBLE (-200 2200);
FORCEPROP 1 LAST PATH I84
J 2
(127 2325);
DISPLAY 0.872340 (127 2325);
PAINT GREEN (127 2325);
DISPLAY INVISIBLE (127 2325);
FORCEADD TAP..6
R 2
(125 2275);
FORCEPROP 3 LASTPIN (75 2275) SIG_NAME M_G_DQ<24>
J 0
(85 2285);
DISPLAY 0.659574 (85 2285);
PAINT MONO (85 2285);
DISPLAY INVISIBLE (85 2285);
FORCEPROP 1 LASTPIN (75 2275) BN 24
J 2
(125 2285);
DISPLAY 0.617021 (125 2285);
PAINT PINK (125 2285);
FORCEPROP 2 LAST CDS_LIB mstr_standard
J 2
(125 2275);
DISPLAY 0.787234 (125 2275);
PAINT MONO (125 2275);
DISPLAY INVISIBLE (125 2275);
FORCEPROP 1 LAST BODY_TYPE PLUMBING
J 2
(125 2225);
DISPLAY 1.234043 (125 2225);
PAINT GREEN (125 2225);
DISPLAY INVISIBLE (125 2225);
FORCEPROP 1 LAST HDL_TAP TRUE
J 2
(-200 2150);
DISPLAY 1.234043 (-200 2150);
PAINT GREEN (-200 2150);
DISPLAY INVISIBLE (-200 2150);
FORCEPROP 1 LAST PATH I85
J 2
(127 2275);
DISPLAY 0.872340 (127 2275);
PAINT GREEN (127 2275);
DISPLAY INVISIBLE (127 2275);
FORCEADD TAP..6
R 2
(125 2475);
FORCEPROP 3 LASTPIN (75 2475) SIG_NAME M_G_DQ<28>
J 0
(85 2485);
DISPLAY 0.659574 (85 2485);
PAINT MONO (85 2485);
DISPLAY INVISIBLE (85 2485);
FORCEPROP 1 LASTPIN (75 2475) BN 28
J 2
(125 2485);
DISPLAY 0.617021 (125 2485);
PAINT PINK (125 2485);
FORCEPROP 2 LAST CDS_LIB mstr_standard
J 2
(125 2475);
DISPLAY 0.787234 (125 2475);
PAINT MONO (125 2475);
DISPLAY INVISIBLE (125 2475);
FORCEPROP 1 LAST BODY_TYPE PLUMBING
J 2
(125 2425);
DISPLAY 1.234043 (125 2425);
PAINT GREEN (125 2425);
DISPLAY INVISIBLE (125 2425);
FORCEPROP 1 LAST HDL_TAP TRUE
J 2
(-200 2350);
DISPLAY 1.234043 (-200 2350);
PAINT GREEN (-200 2350);
DISPLAY INVISIBLE (-200 2350);
FORCEPROP 1 LAST PATH I86
J 2
(127 2475);
DISPLAY 0.872340 (127 2475);
PAINT GREEN (127 2475);
DISPLAY INVISIBLE (127 2475);
FORCEADD TAP..6
R 2
(125 2425);
FORCEPROP 3 LASTPIN (75 2425) SIG_NAME M_G_DQ<27>
J 0
(85 2435);
DISPLAY 0.659574 (85 2435);
PAINT MONO (85 2435);
DISPLAY INVISIBLE (85 2435);
FORCEPROP 1 LASTPIN (75 2425) BN 27
J 2
(125 2435);
DISPLAY 0.617021 (125 2435);
PAINT PINK (125 2435);
FORCEPROP 2 LAST CDS_LIB mstr_standard
J 2
(125 2425);
DISPLAY 0.787234 (125 2425);
PAINT MONO (125 2425);
DISPLAY INVISIBLE (125 2425);
FORCEPROP 1 LAST BODY_TYPE PLUMBING
J 2
(125 2375);
DISPLAY 1.234043 (125 2375);
PAINT GREEN (125 2375);
DISPLAY INVISIBLE (125 2375);
FORCEPROP 1 LAST HDL_TAP TRUE
J 2
(-200 2300);
DISPLAY 1.234043 (-200 2300);
PAINT GREEN (-200 2300);
DISPLAY INVISIBLE (-200 2300);
FORCEPROP 1 LAST PATH I87
J 2
(127 2425);
DISPLAY 0.872340 (127 2425);
PAINT GREEN (127 2425);
DISPLAY INVISIBLE (127 2425);
FORCEADD TAP..6
R 2
(125 2375);
FORCEPROP 3 LASTPIN (75 2375) SIG_NAME M_G_DQ<26>
J 0
(85 2385);
DISPLAY 0.659574 (85 2385);
PAINT MONO (85 2385);
DISPLAY INVISIBLE (85 2385);
FORCEPROP 1 LASTPIN (75 2375) BN 26
J 2
(125 2385);
DISPLAY 0.617021 (125 2385);
PAINT PINK (125 2385);
FORCEPROP 2 LAST CDS_LIB mstr_standard
J 2
(125 2375);
DISPLAY 0.787234 (125 2375);
PAINT MONO (125 2375);
DISPLAY INVISIBLE (125 2375);
FORCEPROP 1 LAST BODY_TYPE PLUMBING
J 2
(125 2325);
DISPLAY 1.234043 (125 2325);
PAINT GREEN (125 2325);
DISPLAY INVISIBLE (125 2325);
FORCEPROP 1 LAST HDL_TAP TRUE
J 2
(-200 2250);
DISPLAY 1.234043 (-200 2250);
PAINT GREEN (-200 2250);
DISPLAY INVISIBLE (-200 2250);
FORCEPROP 1 LAST PATH I88
J 2
(127 2375);
DISPLAY 0.872340 (127 2375);
PAINT GREEN (127 2375);
DISPLAY INVISIBLE (127 2375);
FORCEADD TAP..6
R 2
(125 2525);
FORCEPROP 3 LASTPIN (75 2525) SIG_NAME M_G_DQ<29>
J 0
(85 2535);
DISPLAY 0.659574 (85 2535);
PAINT MONO (85 2535);
DISPLAY INVISIBLE (85 2535);
FORCEPROP 1 LASTPIN (75 2525) BN 29
J 2
(125 2535);
DISPLAY 0.617021 (125 2535);
PAINT PINK (125 2535);
FORCEPROP 2 LAST CDS_LIB mstr_standard
J 2
(125 2525);
DISPLAY 0.787234 (125 2525);
PAINT MONO (125 2525);
DISPLAY INVISIBLE (125 2525);
FORCEPROP 1 LAST BODY_TYPE PLUMBING
J 2
(125 2475);
DISPLAY 1.234043 (125 2475);
PAINT GREEN (125 2475);
DISPLAY INVISIBLE (125 2475);
FORCEPROP 1 LAST HDL_TAP TRUE
J 2
(-200 2400);
DISPLAY 1.234043 (-200 2400);
PAINT GREEN (-200 2400);
DISPLAY INVISIBLE (-200 2400);
FORCEPROP 1 LAST PATH I89
J 2
(127 2525);
DISPLAY 0.872340 (127 2525);
PAINT GREEN (127 2525);
DISPLAY INVISIBLE (127 2525);
FORCEADD OFFPAGE..1
(-2025 1175);
FORCEPROP 2 LAST $XR5 82 
J 0
(-2726 1175);
DISPLAY 0.638298 (-2726 1175);
PAINT MONO (-2726 1175);
FORCEPROP 2 LAST $XR4 81 
J 0
(-2636 1175);
DISPLAY 0.638298 (-2636 1175);
PAINT MONO (-2636 1175);
FORCEPROP 2 LAST $XR3 80 
J 0
(-2546 1175);
DISPLAY 0.638298 (-2546 1175);
PAINT MONO (-2546 1175);
FORCEPROP 2 LAST $XR2 79 
J 0
(-2456 1175);
DISPLAY 0.638298 (-2456 1175);
PAINT MONO (-2456 1175);
FORCEPROP 2 LAST $XR1 77 
J 0
(-2366 1175);
DISPLAY 0.638298 (-2366 1175);
PAINT MONO (-2366 1175);
FORCEPROP 2 LAST $XR0 99 
J 0
(-2276 1175);
DISPLAY 0.638298 (-2276 1175);
PAINT MONO (-2276 1175);
FORCEPROP 2 LAST CDS_LIB mstr_standard
J 0
(-2025 1175);
DISPLAY 0.787234 (-2025 1175);
PAINT MONO (-2025 1175);
DISPLAY INVISIBLE (-2025 1175);
FORCEPROP 1 LAST OFFPAGE TRUE
J 0
(-1700 1050);
DISPLAY 0.936170 (-1700 1050);
PAINT GREEN (-1700 1050);
DISPLAY INVISIBLE (-1700 1050);
FORCEPROP 1 LAST COMMENT_BODY TRUE
J 0
(-1900 1075);
DISPLAY 0.936170 (-1900 1075);
PAINT GREEN (-1900 1075);
DISPLAY INVISIBLE (-1900 1075);
FORCEPROP 2 LAST PATH I9
J 0
(-2275 1225);
DISPLAY 1.021277 (-2275 1225);
PAINT ORANGE (-2275 1225);
DISPLAY INVISIBLE (-2275 1225);
FORCEADD TAP..6
R 2
(125 2575);
FORCEPROP 3 LASTPIN (75 2575) SIG_NAME M_G_DQ<30>
J 0
(85 2585);
DISPLAY 0.659574 (85 2585);
PAINT MONO (85 2585);
DISPLAY INVISIBLE (85 2585);
FORCEPROP 1 LASTPIN (75 2575) BN 30
J 2
(125 2585);
DISPLAY 0.617021 (125 2585);
PAINT PINK (125 2585);
FORCEPROP 2 LAST CDS_LIB mstr_standard
J 2
(125 2575);
DISPLAY 0.787234 (125 2575);
PAINT MONO (125 2575);
DISPLAY INVISIBLE (125 2575);
FORCEPROP 1 LAST BODY_TYPE PLUMBING
J 2
(125 2525);
DISPLAY 1.234043 (125 2525);
PAINT GREEN (125 2525);
DISPLAY INVISIBLE (125 2525);
FORCEPROP 1 LAST HDL_TAP TRUE
J 2
(-200 2450);
DISPLAY 1.234043 (-200 2450);
PAINT GREEN (-200 2450);
DISPLAY INVISIBLE (-200 2450);
FORCEPROP 1 LAST PATH I90
J 2
(127 2575);
DISPLAY 0.872340 (127 2575);
PAINT GREEN (127 2575);
DISPLAY INVISIBLE (127 2575);
FORCEADD TAP..6
R 2
(125 2675);
FORCEPROP 3 LASTPIN (75 2675) SIG_NAME M_G_DQ<32>
J 0
(85 2685);
DISPLAY 0.659574 (85 2685);
PAINT MONO (85 2685);
DISPLAY INVISIBLE (85 2685);
FORCEPROP 1 LASTPIN (75 2675) BN 32
J 2
(125 2685);
DISPLAY 0.617021 (125 2685);
PAINT PINK (125 2685);
FORCEPROP 2 LAST CDS_LIB mstr_standard
J 2
(125 2675);
DISPLAY 0.787234 (125 2675);
PAINT MONO (125 2675);
DISPLAY INVISIBLE (125 2675);
FORCEPROP 1 LAST BODY_TYPE PLUMBING
J 2
(125 2625);
DISPLAY 1.234043 (125 2625);
PAINT GREEN (125 2625);
DISPLAY INVISIBLE (125 2625);
FORCEPROP 1 LAST HDL_TAP TRUE
J 2
(-200 2550);
DISPLAY 1.234043 (-200 2550);
PAINT GREEN (-200 2550);
DISPLAY INVISIBLE (-200 2550);
FORCEPROP 1 LAST PATH I91
J 2
(127 2675);
DISPLAY 0.872340 (127 2675);
PAINT GREEN (127 2675);
DISPLAY INVISIBLE (127 2675);
FORCEADD TAP..6
R 2
(125 2725);
FORCEPROP 3 LASTPIN (75 2725) SIG_NAME M_G_DQ<33>
J 0
(85 2735);
DISPLAY 0.659574 (85 2735);
PAINT MONO (85 2735);
DISPLAY INVISIBLE (85 2735);
FORCEPROP 1 LASTPIN (75 2725) BN 33
J 2
(125 2735);
DISPLAY 0.617021 (125 2735);
PAINT PINK (125 2735);
FORCEPROP 2 LAST CDS_LIB mstr_standard
J 2
(125 2725);
DISPLAY 0.787234 (125 2725);
PAINT MONO (125 2725);
DISPLAY INVISIBLE (125 2725);
FORCEPROP 1 LAST BODY_TYPE PLUMBING
J 2
(125 2675);
DISPLAY 1.234043 (125 2675);
PAINT GREEN (125 2675);
DISPLAY INVISIBLE (125 2675);
FORCEPROP 1 LAST HDL_TAP TRUE
J 2
(-200 2600);
DISPLAY 1.234043 (-200 2600);
PAINT GREEN (-200 2600);
DISPLAY INVISIBLE (-200 2600);
FORCEPROP 1 LAST PATH I92
J 2
(127 2725);
DISPLAY 0.872340 (127 2725);
PAINT GREEN (127 2725);
DISPLAY INVISIBLE (127 2725);
FORCEADD TAP..6
R 2
(125 2625);
FORCEPROP 3 LASTPIN (75 2625) SIG_NAME M_G_DQ<31>
J 0
(85 2635);
DISPLAY 0.659574 (85 2635);
PAINT MONO (85 2635);
DISPLAY INVISIBLE (85 2635);
FORCEPROP 1 LASTPIN (75 2625) BN 31
J 2
(125 2635);
DISPLAY 0.617021 (125 2635);
PAINT PINK (125 2635);
FORCEPROP 2 LAST CDS_LIB mstr_standard
J 2
(125 2625);
DISPLAY 0.787234 (125 2625);
PAINT MONO (125 2625);
DISPLAY INVISIBLE (125 2625);
FORCEPROP 1 LAST BODY_TYPE PLUMBING
J 2
(125 2575);
DISPLAY 1.234043 (125 2575);
PAINT GREEN (125 2575);
DISPLAY INVISIBLE (125 2575);
FORCEPROP 1 LAST HDL_TAP TRUE
J 2
(-200 2500);
DISPLAY 1.234043 (-200 2500);
PAINT GREEN (-200 2500);
DISPLAY INVISIBLE (-200 2500);
FORCEPROP 1 LAST PATH I93
J 2
(127 2625);
DISPLAY 0.872340 (127 2625);
PAINT GREEN (127 2625);
DISPLAY INVISIBLE (127 2625);
FORCEADD TAP..6
R 2
(125 2825);
FORCEPROP 3 LASTPIN (75 2825) SIG_NAME M_G_DQ<35>
J 0
(85 2835);
DISPLAY 0.659574 (85 2835);
PAINT MONO (85 2835);
DISPLAY INVISIBLE (85 2835);
FORCEPROP 1 LASTPIN (75 2825) BN 35
J 2
(125 2835);
DISPLAY 0.617021 (125 2835);
PAINT PINK (125 2835);
FORCEPROP 2 LAST CDS_LIB mstr_standard
J 2
(125 2825);
DISPLAY 0.787234 (125 2825);
PAINT MONO (125 2825);
DISPLAY INVISIBLE (125 2825);
FORCEPROP 1 LAST BODY_TYPE PLUMBING
J 2
(125 2775);
DISPLAY 1.234043 (125 2775);
PAINT GREEN (125 2775);
DISPLAY INVISIBLE (125 2775);
FORCEPROP 1 LAST HDL_TAP TRUE
J 2
(-200 2700);
DISPLAY 1.234043 (-200 2700);
PAINT GREEN (-200 2700);
DISPLAY INVISIBLE (-200 2700);
FORCEPROP 1 LAST PATH I94
J 2
(127 2825);
DISPLAY 0.872340 (127 2825);
PAINT GREEN (127 2825);
DISPLAY INVISIBLE (127 2825);
FORCEADD TAP..6
R 2
(125 2775);
FORCEPROP 3 LASTPIN (75 2775) SIG_NAME M_G_DQ<34>
J 0
(85 2785);
DISPLAY 0.659574 (85 2785);
PAINT MONO (85 2785);
DISPLAY INVISIBLE (85 2785);
FORCEPROP 1 LASTPIN (75 2775) BN 34
J 2
(125 2785);
DISPLAY 0.617021 (125 2785);
PAINT PINK (125 2785);
FORCEPROP 2 LAST CDS_LIB mstr_standard
J 2
(125 2775);
DISPLAY 0.787234 (125 2775);
PAINT MONO (125 2775);
DISPLAY INVISIBLE (125 2775);
FORCEPROP 1 LAST BODY_TYPE PLUMBING
J 2
(125 2725);
DISPLAY 1.234043 (125 2725);
PAINT GREEN (125 2725);
DISPLAY INVISIBLE (125 2725);
FORCEPROP 1 LAST HDL_TAP TRUE
J 2
(-200 2650);
DISPLAY 1.234043 (-200 2650);
PAINT GREEN (-200 2650);
DISPLAY INVISIBLE (-200 2650);
FORCEPROP 1 LAST PATH I95
J 2
(127 2775);
DISPLAY 0.872340 (127 2775);
PAINT GREEN (127 2775);
DISPLAY INVISIBLE (127 2775);
FORCEADD PVDDQ_GHJ..1
(400 2300);
FORCEPROP 3 LASTPIN (400 2250) SIG_NAME PVDDQ_GHJ\g
J 0
(410 2260);
DISPLAY 0.659574 (410 2260);
PAINT MONO (410 2260);
DISPLAY INVISIBLE (410 2260);
FORCEPROP 1 LAST VOLTAGE 1.2V
J 0
(355 2257);
DISPLAY 0.340426 (355 2257);
PAINT SKYBLUE (355 2257);
DISPLAY INVISIBLE (355 2257);
FORCEPROP 2 LAST BOM_COST MEM
J 0
(400 2305);
PAINT ORANGE (400 2305);
DISPLAY INVISIBLE (400 2305);
FORCEPROP 2 LAST CDS_LIB mstr_symbols
J 0
(400 2300);
PAINT ORANGE (400 2300);
DISPLAY INVISIBLE (400 2300);
FORCEPROP 1 LAST BODY_TYPE PLUMBING
J 0
(355 2257);
DISPLAY 0.340426 (355 2257);
PAINT GREEN (355 2257);
DISPLAY INVISIBLE (355 2257);
FORCEPROP 1 LAST PATH I96
J 0
(450 2325);
DISPLAY 0.872340 (450 2325);
PAINT AQUA (450 2325);
DISPLAY INVISIBLE (450 2325);
FORCEPROP 2 LAST ROOM DDR4_GH_G
J 0
(400 2400);
DISPLAY 0.787234 (400 2400);
PAINT ORANGE (400 2400);
DISPLAY INVISIBLE (400 2400);
FORCEPROP 1 LAST HDL_POWER PVDDQ_GHJ
J 1
(400 2350);
DISPLAY 0.872340 (400 2350);
PAINT GREEN (400 2350);
DISPLAY INVISIBLE (400 2350);
FORCEADD PVTT_GHJ..1
(600 2450);
FORCEPROP 3 LASTPIN (600 2400) SIG_NAME PVTT_GHJ\g
J 0
(610 2410);
DISPLAY 0.659574 (610 2410);
PAINT MONO (610 2410);
DISPLAY INVISIBLE (610 2410);
FORCEPROP 1 LAST VOLTAGE 0.6V
J 0
(555 2407);
DISPLAY 0.340426 (555 2407);
PAINT SKYBLUE (555 2407);
DISPLAY INVISIBLE (555 2407);
FORCEPROP 2 LAST BOM_COST MEM
J 0
(600 2455);
PAINT ORANGE (600 2455);
DISPLAY INVISIBLE (600 2455);
FORCEPROP 2 LAST CDS_LIB mstr_symbols
J 0
(600 2450);
PAINT ORANGE (600 2450);
DISPLAY INVISIBLE (600 2450);
FORCEPROP 1 LAST BODY_TYPE PLUMBING
J 0
(555 2407);
DISPLAY 0.340426 (555 2407);
PAINT GREEN (555 2407);
DISPLAY INVISIBLE (555 2407);
FORCEPROP 1 LAST PATH I97
J 0
(650 2475);
DISPLAY 0.872340 (650 2475);
PAINT AQUA (650 2475);
DISPLAY INVISIBLE (650 2475);
FORCEPROP 2 LAST ROOM DDR4_GH_G
J 0
(600 2550);
DISPLAY 0.787234 (600 2550);
PAINT ORANGE (600 2550);
DISPLAY INVISIBLE (600 2550);
FORCEPROP 1 LAST HDL_POWER PVTT_GHJ
J 1
(600 2500);
DISPLAY 0.872340 (600 2500);
PAINT GREEN (600 2500);
DISPLAY INVISIBLE (600 2500);
FORCEADD TAP..6
R 2
(125 2875);
FORCEPROP 3 LASTPIN (75 2875) SIG_NAME M_G_DQ<36>
J 0
(85 2885);
DISPLAY 0.659574 (85 2885);
PAINT MONO (85 2885);
DISPLAY INVISIBLE (85 2885);
FORCEPROP 1 LASTPIN (75 2875) BN 36
J 2
(125 2885);
DISPLAY 0.617021 (125 2885);
PAINT PINK (125 2885);
FORCEPROP 2 LAST CDS_LIB mstr_standard
J 2
(125 2875);
DISPLAY 0.787234 (125 2875);
PAINT MONO (125 2875);
DISPLAY INVISIBLE (125 2875);
FORCEPROP 1 LAST BODY_TYPE PLUMBING
J 2
(125 2825);
DISPLAY 1.234043 (125 2825);
PAINT GREEN (125 2825);
DISPLAY INVISIBLE (125 2825);
FORCEPROP 1 LAST HDL_TAP TRUE
J 2
(-200 2750);
DISPLAY 1.234043 (-200 2750);
PAINT GREEN (-200 2750);
DISPLAY INVISIBLE (-200 2750);
FORCEPROP 1 LAST PATH I98
J 2
(127 2875);
DISPLAY 0.872340 (127 2875);
PAINT GREEN (127 2875);
DISPLAY INVISIBLE (127 2875);
FORCEADD TAP..6
R 2
(125 2975);
FORCEPROP 3 LASTPIN (75 2975) SIG_NAME M_G_DQ<38>
J 0
(85 2985);
DISPLAY 0.659574 (85 2985);
PAINT MONO (85 2985);
DISPLAY INVISIBLE (85 2985);
FORCEPROP 1 LASTPIN (75 2975) BN 38
J 2
(125 2985);
DISPLAY 0.617021 (125 2985);
PAINT PINK (125 2985);
FORCEPROP 2 LAST CDS_LIB mstr_standard
J 2
(125 2975);
DISPLAY 0.787234 (125 2975);
PAINT MONO (125 2975);
DISPLAY INVISIBLE (125 2975);
FORCEPROP 1 LAST BODY_TYPE PLUMBING
J 2
(125 2925);
DISPLAY 1.234043 (125 2925);
PAINT GREEN (125 2925);
DISPLAY INVISIBLE (125 2925);
FORCEPROP 1 LAST HDL_TAP TRUE
J 2
(-200 2850);
DISPLAY 1.234043 (-200 2850);
PAINT GREEN (-200 2850);
DISPLAY INVISIBLE (-200 2850);
FORCEPROP 1 LAST PATH I99
J 2
(127 2975);
DISPLAY 0.872340 (127 2975);
PAINT GREEN (127 2975);
DISPLAY INVISIBLE (127 2975);
FORCEADD BOM_NOTE..1
(-3275 5000);
FORCEPROP 0 LAST L1 UNSTUFF FOR SKU B
J 0
(-3425 4900);
DISPLAY 1.063830 (-3425 4900);
PAINT WHITE (-3425 4900);
FORCEPROP 2 LAST BOM_COST SB
J 0
(-3425 4975);
DISPLAY 1.361702 (-3425 4975);
PAINT ORANGE (-3425 4975);
DISPLAY INVISIBLE (-3425 4975);
FORCEPROP 2 LAST CDS_LIB mstr_symbols
J 0
(-3275 5000);
PAINT ORANGE (-3275 5000);
DISPLAY INVISIBLE (-3275 5000);
FORCEPROP 1 LAST COMMENT_BODY TRUE
J 0
(-3250 5100);
DISPLAY 1.319149 (-3250 5100);
PAINT ORANGE (-3250 5100);
DISPLAY INVISIBLE (-3250 5100);
FORCEPROP 2 LAST ROOM SB_HEADERS
J 0
(-3425 4975);
DISPLAY 1.361702 (-3425 4975);
PAINT ORANGE (-3425 4975);
DISPLAY INVISIBLE (-3425 4975);
FORCEADD INTEL_CORP_BPAGE..1
(4400 200);
FORCEPROP 1 LAST CDS_CON_LAST_MODIFIED Fri Jun 16 17:48:29 2017
J 0
(2975 525);
PAINT ORANGE (2975 525);
DISPLAY INVISIBLE (2975 525);
FORCEPROP 1 LAST CUSTOM_TXT_CDS <CURRENT_DESIGN_SHEET> OF <TOTAL_DESIGN_SHEETS>
J 0
(3900 225);
PAINT ORANGE (3900 225);
FORCEPROP 1 LAST CUSTOM_TXT_CDS <CON_LAST_MODIFIED>
J 0
(400 300);
PAINT ORANGE (400 300);
FORCEPROP 2 LAST CUSTOM_TXT_CDS <XR_PAGE_TITLE>
J 0
(-3490 5450);
DISPLAY 0.638298 (-3490 5450);
PAINT PINK (-3490 5450);
DISPLAY INVISIBLE (-3490 5450);
FORCEPROP 1 LAST SCH_TITLE CPU1 DDR4 CH G DIMM1
J 0
(-3550 250);
DISPLAY 1.212766 (-3550 250);
PAINT ORANGE (-3550 250);
FORCEPROP 2 LAST CDS_LIB mstr_symbols
J 0
(4400 200);
PAINT MONO (4400 200);
DISPLAY INVISIBLE (4400 200);
FORCEPROP 2 LAST PAGE_BORDER TRUE
J 0
(-3490 5450);
DISPLAY 0.638298 (-3490 5450);
PAINT PINK (-3490 5450);
DISPLAY INVISIBLE (-3490 5450);
FORCEPROP 1 LAST COMMENT_BODY TRUE
J 0
(4412 212);
DISPLAY 0.468085 (4412 212);
PAINT GREEN (4412 212);
DISPLAY INVISIBLE (4412 212);
FORCEPROP 2 LAST CDS_XR_PAGE_TITLE CR-78 : @BASEBOARD_FAB2_LIB.BASEBOARD_FAB2(SCH_1):PAGE78
J 0
(-3490 5450);
DISPLAY 0.638298 (-3490 5450);
PAINT PINK (-3490 5450);
DISPLAY INVISIBLE (-3490 5450);
WIRE 16 -1 (-2675 775)(-2675 675);
WIRE 16 -1 (750 2700)(750 2600);
WIRE 16 -1 (750 2550)(750 2600);
WIRE 16 -1 (750 2600)(950 2600);
WIRE 16 -1 (750 2500)(750 2550);
WIRE 16 -1 (750 2550)(950 2550);
WIRE 16 -1 (750 2450)(750 2500);
WIRE 16 -1 (750 2500)(950 2500);
WIRE 16 -1 (750 2400)(750 2450);
WIRE 16 -1 (750 2450)(950 2450);
WIRE 16 -1 (750 2400)(950 2400);
WIRE 16 -1 (2850 750)(2850 850);
WIRE 16 -1 (2850 850)(2850 900);
WIRE 16 -1 (2850 850)(3050 850);
WIRE 16 -1 (2850 900)(2850 950);
WIRE 16 -1 (2850 900)(3050 900);
WIRE 16 -1 (2850 950)(2850 1000);
WIRE 16 -1 (2850 950)(3050 950);
WIRE 16 -1 (2850 1000)(2850 1050);
WIRE 16 -1 (2850 1000)(3050 1000);
WIRE 16 -1 (2850 1050)(2850 1100);
WIRE 16 -1 (2850 1050)(3050 1050);
WIRE 16 -1 (2850 1100)(2850 1150);
WIRE 16 -1 (2850 1100)(3050 1100);
WIRE 16 -1 (2850 1150)(2850 1200);
WIRE 16 -1 (2850 1150)(3050 1150);
WIRE 16 -1 (2850 1200)(2850 1250);
WIRE 16 -1 (2850 1200)(3050 1200);
WIRE 16 -1 (2850 1250)(2850 1300);
WIRE 16 -1 (2850 1250)(3050 1250);
WIRE 16 -1 (2850 1300)(2850 1350);
WIRE 16 -1 (2850 1300)(3050 1300);
WIRE 16 -1 (2850 1350)(2850 1400);
WIRE 16 -1 (2850 1350)(3050 1350);
WIRE 16 -1 (2850 1400)(2850 1450);
WIRE 16 -1 (2850 1400)(3050 1400);
WIRE 16 -1 (2850 1450)(2850 1500);
WIRE 16 -1 (2850 1450)(3050 1450);
WIRE 16 -1 (2850 1500)(2850 1550);
WIRE 16 -1 (2850 1500)(3050 1500);
WIRE 16 -1 (2850 1550)(2850 1600);
WIRE 16 -1 (2850 1550)(3050 1550);
WIRE 16 -1 (2850 1600)(2850 1650);
WIRE 16 -1 (2850 1600)(3050 1600);
WIRE 16 -1 (2850 1650)(2850 1700);
WIRE 16 -1 (2850 1650)(3050 1650);
WIRE 16 -1 (2850 1700)(2850 1750);
WIRE 16 -1 (2850 1700)(3050 1700);
WIRE 16 -1 (2850 1750)(2850 1800);
WIRE 16 -1 (2850 1750)(3050 1750);
WIRE 16 -1 (2850 1800)(2850 1850);
WIRE 16 -1 (2850 1800)(3050 1800);
WIRE 16 -1 (2850 1850)(2850 1900);
WIRE 16 -1 (2850 1850)(3050 1850);
WIRE 16 -1 (2850 1900)(2850 1950);
WIRE 16 -1 (2850 1900)(3050 1900);
WIRE 16 -1 (2850 1950)(2850 2000);
WIRE 16 -1 (2850 1950)(3050 1950);
WIRE 16 -1 (2850 2000)(2850 2050);
WIRE 16 -1 (2850 2000)(3050 2000);
WIRE 16 -1 (2850 2050)(2850 2100);
WIRE 16 -1 (2850 2050)(3050 2050);
WIRE 16 -1 (2850 2100)(2850 2150);
WIRE 16 -1 (2850 2100)(3050 2100);
WIRE 16 -1 (2850 2150)(2850 2200);
WIRE 16 -1 (2850 2150)(3050 2150);
WIRE 16 -1 (2850 2200)(2850 2250);
WIRE 16 -1 (2850 2200)(3050 2200);
WIRE 16 -1 (2850 2250)(2850 2300);
WIRE 16 -1 (2850 2250)(3050 2250);
WIRE 16 -1 (2850 2300)(2850 2350);
WIRE 16 -1 (2850 2300)(3050 2300);
WIRE 16 -1 (2850 2350)(2850 2400);
WIRE 16 -1 (2850 2350)(3050 2350);
WIRE 16 -1 (2850 2400)(2850 2450);
WIRE 16 -1 (2850 2400)(3050 2400);
WIRE 16 -1 (2850 2450)(2850 2500);
WIRE 16 -1 (2850 2450)(3050 2450);
WIRE 16 -1 (2850 2500)(2850 2550);
WIRE 16 -1 (2850 2500)(3050 2500);
WIRE 16 -1 (2850 2550)(2850 2600);
WIRE 16 -1 (2850 2550)(3050 2550);
WIRE 16 -1 (2850 2600)(2850 2650);
WIRE 16 -1 (2850 2600)(3050 2600);
WIRE 16 -1 (2850 2650)(2850 2700);
WIRE 16 -1 (2850 2650)(3050 2650);
WIRE 16 -1 (2850 2700)(2850 2750);
WIRE 16 -1 (2850 2700)(3050 2700);
WIRE 16 -1 (2850 2750)(2850 2800);
WIRE 16 -1 (2850 2750)(3050 2750);
WIRE 16 -1 (2850 2800)(2850 2850);
WIRE 16 -1 (2850 2800)(3050 2800);
WIRE 16 -1 (2850 2850)(2850 2900);
WIRE 16 -1 (2850 2850)(3050 2850);
WIRE 16 -1 (2850 2900)(2850 2950);
WIRE 16 -1 (2850 2900)(3050 2900);
WIRE 16 -1 (2850 2950)(2850 3000);
WIRE 16 -1 (2850 2950)(3050 2950);
WIRE 16 -1 (2850 3000)(2850 3050);
WIRE 16 -1 (2850 3000)(3050 3000);
WIRE 16 -1 (2850 3050)(2850 3100);
WIRE 16 -1 (2850 3050)(3050 3050);
WIRE 16 -1 (2850 3100)(2850 3150);
WIRE 16 -1 (2850 3100)(3050 3100);
WIRE 16 -1 (2850 3150)(3050 3150);
WIRE 16 -1 (4250 750)(4250 850);
WIRE 16 -1 (4250 850)(4250 900);
WIRE 16 -1 (4250 850)(4050 850);
WIRE 16 -1 (4250 900)(4250 950);
WIRE 16 -1 (4250 900)(4050 900);
WIRE 16 -1 (4250 950)(4250 1000);
WIRE 16 -1 (4250 950)(4050 950);
WIRE 16 -1 (4250 1000)(4250 1050);
WIRE 16 -1 (4250 1000)(4050 1000);
WIRE 16 -1 (4250 1050)(4250 1100);
WIRE 16 -1 (4250 1050)(4050 1050);
WIRE 16 -1 (4250 1100)(4250 1150);
WIRE 16 -1 (4250 1100)(4050 1100);
WIRE 16 -1 (4250 1150)(4250 1200);
WIRE 16 -1 (4250 1150)(4050 1150);
WIRE 16 -1 (4250 1200)(4250 1250);
WIRE 16 -1 (4250 1200)(4050 1200);
WIRE 16 -1 (4250 1250)(4250 1300);
WIRE 16 -1 (4250 1250)(4050 1250);
WIRE 16 -1 (4250 1300)(4250 1350);
WIRE 16 -1 (4250 1300)(4050 1300);
WIRE 16 -1 (4250 1350)(4250 1400);
WIRE 16 -1 (4250 1350)(4050 1350);
WIRE 16 -1 (4250 1400)(4250 1450);
WIRE 16 -1 (4250 1400)(4050 1400);
WIRE 16 -1 (4250 1450)(4250 1500);
WIRE 16 -1 (4250 1450)(4050 1450);
WIRE 16 -1 (4250 1500)(4250 1550);
WIRE 16 -1 (4250 1500)(4050 1500);
WIRE 16 -1 (4250 1550)(4250 1600);
WIRE 16 -1 (4250 1550)(4050 1550);
WIRE 16 -1 (4250 1600)(4250 1650);
WIRE 16 -1 (4250 1600)(4050 1600);
WIRE 16 -1 (4250 1650)(4250 1700);
WIRE 16 -1 (4250 1650)(4050 1650);
WIRE 16 -1 (4250 1700)(4250 1750);
WIRE 16 -1 (4250 1700)(4050 1700);
WIRE 16 -1 (4250 1750)(4250 1800);
WIRE 16 -1 (4250 1750)(4050 1750);
WIRE 16 -1 (4250 1800)(4250 1850);
WIRE 16 -1 (4250 1800)(4050 1800);
WIRE 16 -1 (4250 1850)(4250 1900);
WIRE 16 -1 (4250 1850)(4050 1850);
WIRE 16 -1 (4250 1900)(4250 1950);
WIRE 16 -1 (4250 1900)(4050 1900);
WIRE 16 -1 (4250 1950)(4250 2000);
WIRE 16 -1 (4250 1950)(4050 1950);
WIRE 16 -1 (4250 2000)(4250 2050);
WIRE 16 -1 (4250 2000)(4050 2000);
WIRE 16 -1 (4250 2050)(4250 2100);
WIRE 16 -1 (4250 2050)(4050 2050);
WIRE 16 -1 (4250 2100)(4250 2150);
WIRE 16 -1 (4250 2100)(4050 2100);
WIRE 16 -1 (4250 2150)(4250 2200);
WIRE 16 -1 (4250 2150)(4050 2150);
WIRE 16 -1 (4250 2200)(4250 2250);
WIRE 16 -1 (4250 2200)(4050 2200);
WIRE 16 -1 (4250 2250)(4250 2300);
WIRE 16 -1 (4250 2250)(4050 2250);
WIRE 16 -1 (4250 2300)(4250 2350);
WIRE 16 -1 (4250 2300)(4050 2300);
WIRE 16 -1 (4250 2350)(4250 2400);
WIRE 16 -1 (4250 2350)(4050 2350);
WIRE 16 -1 (4250 2400)(4250 2450);
WIRE 16 -1 (4250 2400)(4050 2400);
WIRE 16 -1 (4250 2450)(4250 2500);
WIRE 16 -1 (4250 2450)(4050 2450);
WIRE 16 -1 (4250 2500)(4250 2550);
WIRE 16 -1 (4250 2500)(4050 2500);
WIRE 16 -1 (4250 2550)(4250 2600);
WIRE 16 -1 (4250 2550)(4050 2550);
WIRE 16 -1 (4250 2600)(4250 2650);
WIRE 16 -1 (4250 2600)(4050 2600);
WIRE 16 -1 (4250 2650)(4250 2700);
WIRE 16 -1 (4250 2650)(4050 2650);
WIRE 16 -1 (4250 2700)(4250 2750);
WIRE 16 -1 (4250 2700)(4050 2700);
WIRE 16 -1 (4250 2750)(4250 2800);
WIRE 16 -1 (4250 2750)(4050 2750);
WIRE 16 -1 (4250 2800)(4250 2850);
WIRE 16 -1 (4250 2800)(4050 2800);
WIRE 16 -1 (4250 2850)(4250 2900);
WIRE 16 -1 (4250 2850)(4050 2850);
WIRE 16 -1 (4250 2900)(4250 2950);
WIRE 16 -1 (4250 2900)(4050 2900);
WIRE 16 -1 (4250 2950)(4250 3000);
WIRE 16 -1 (4250 2950)(4050 2950);
WIRE 16 -1 (4250 3000)(4250 3050);
WIRE 16 -1 (4250 3000)(4050 3000);
WIRE 16 -1 (4250 3050)(4250 3100);
WIRE 16 -1 (4250 3050)(4050 3050);
WIRE 16 -1 (4250 3100)(4250 3150);
WIRE 16 -1 (4250 3100)(4050 3100);
WIRE 16 -1 (4250 3150)(4050 3150);
WIRE 16 -1 (2150 2600)(2150 2675);
WIRE 16 -1 (2150 2550)(2150 2600);
WIRE 16 -1 (1950 2600)(2150 2600);
WIRE 16 -1 (1950 2550)(2150 2550);
WIRE 16 -1 (-3325 1375)(-3325 1275);
WIRE 16 -1 (-3325 1375)(-1350 1375);
WIRE 16 -1 (-1350 1375)(-1350 1325);
WIRE 16 -1 (-1350 1375)(-1125 1375);
WIRE 16 -1 (-1350 1325)(-1125 1325);
WIRE 16 -1 (-3325 1525)(-3325 1425);
WIRE 16 -1 (-1425 1425)(-3325 1425);
WIRE 16 -1 (-1425 1425)(-1425 1275);
WIRE 16 -1 (-1125 1425)(-1425 1425);
WIRE 16 -1 (-1125 1275)(-1425 1275);
WIRE 16 -1 (400 2250)(400 2150);
WIRE 16 -1 (400 2150)(750 2150);
WIRE 16 -1 (750 2100)(750 2150);
WIRE 16 -1 (750 2150)(950 2150);
WIRE 16 -1 (750 2050)(750 2100);
WIRE 16 -1 (750 2100)(950 2100);
WIRE 16 -1 (750 2000)(750 2050);
WIRE 16 -1 (750 2050)(950 2050);
WIRE 16 -1 (750 1950)(750 2000);
WIRE 16 -1 (750 2000)(950 2000);
WIRE 16 -1 (750 1900)(750 1950);
WIRE 16 -1 (750 1950)(950 1950);
WIRE 16 -1 (750 1850)(750 1900);
WIRE 16 -1 (750 1900)(950 1900);
WIRE 16 -1 (750 1800)(750 1850);
WIRE 16 -1 (750 1850)(950 1850);
WIRE 16 -1 (750 1750)(750 1800);
WIRE 16 -1 (750 1800)(950 1800);
WIRE 16 -1 (750 1700)(750 1750);
WIRE 16 -1 (750 1750)(950 1750);
WIRE 16 -1 (750 1650)(750 1700);
WIRE 16 -1 (750 1700)(950 1700);
WIRE 16 -1 (750 1600)(750 1650);
WIRE 16 -1 (750 1650)(950 1650);
WIRE 16 -1 (750 1550)(750 1600);
WIRE 16 -1 (750 1600)(950 1600);
WIRE 16 -1 (750 1500)(750 1550);
WIRE 16 -1 (750 1550)(950 1550);
WIRE 16 -1 (750 1450)(750 1500);
WIRE 16 -1 (750 1500)(950 1500);
WIRE 16 -1 (750 1400)(750 1450);
WIRE 16 -1 (750 1450)(950 1450);
WIRE 16 -1 (750 1350)(750 1400);
WIRE 16 -1 (750 1400)(950 1400);
WIRE 16 -1 (750 1300)(750 1350);
WIRE 16 -1 (750 1350)(950 1350);
WIRE 16 -1 (750 1250)(750 1300);
WIRE 16 -1 (750 1300)(950 1300);
WIRE 16 -1 (750 1200)(750 1250);
WIRE 16 -1 (750 1250)(950 1250);
WIRE 16 -1 (750 1150)(750 1200);
WIRE 16 -1 (750 1200)(950 1200);
WIRE 16 -1 (750 1100)(750 1150);
WIRE 16 -1 (750 1150)(950 1150);
WIRE 16 -1 (750 1050)(750 1100);
WIRE 16 -1 (750 1100)(950 1100);
WIRE 16 -1 (750 1000)(750 1050);
WIRE 16 -1 (750 1050)(950 1050);
WIRE 16 -1 (750 950)(750 1000);
WIRE 16 -1 (750 1000)(950 1000);
WIRE 16 -1 (750 900)(750 950);
WIRE 16 -1 (750 950)(950 950);
WIRE 16 -1 (750 900)(950 900);
WIRE 16 -1 (600 2400)(600 2300);
WIRE 16 -1 (600 2300)(750 2300);
WIRE 16 -1 (750 2250)(750 2300);
WIRE 16 -1 (750 2300)(950 2300);
WIRE 16 -1 (750 2250)(950 2250);
WIRE 17 -1 (2700 3125)(2700 3225);
WIRE 17 -1 (2700 3225)(2700 3325);
WIRE 17 -1 (2700 3325)(2700 3425);
WIRE 17 -1 (2700 3425)(2700 3525);
WIRE 17 -1 (2700 3525)(2700 3625);
WIRE 17 -1 (2700 3625)(2700 3725);
WIRE 17 -1 (2700 3725)(2700 3825);
WIRE 17 -1 (2700 3825)(2700 3925);
WIRE 17 -1 (2700 3925)(2700 4025);
WIRE 17 -1 (2700 4025)(2700 4125);
WIRE 17 -1 (2700 4125)(2700 4225);
WIRE 17 -1 (2700 4225)(2700 4325);
WIRE 17 -1 (2700 4325)(2700 4425);
WIRE 17 -1 (2700 4425)(2700 4525);
WIRE 17 -1 (2700 4525)(2700 4625);
WIRE 17 -1 (3300 4850)(2700 4850);
FORCEPROP 2 LAST SIG_NAME M_G_DQS_DN<17:0>
J 0
(2725 4860);
DISPLAY 0.617021 (2725 4860);
PAINT ORANGE (2725 4860);
WIRE 17 -1 (2700 4825)(2700 4850);
WIRE 17 -1 (2700 4625)(2700 4725);
WIRE 17 -1 (2700 4725)(2700 4825);
WIRE 17 -1 (2500 3175)(2500 3275);
WIRE 17 -1 (2500 3275)(2500 3375);
WIRE 17 -1 (2500 3375)(2500 3475);
WIRE 17 -1 (2500 3475)(2500 3575);
WIRE 17 -1 (2500 3575)(2500 3675);
WIRE 17 -1 (2500 3675)(2500 3775);
WIRE 17 -1 (2500 3775)(2500 3875);
WIRE 17 -1 (2500 3875)(2500 3975);
WIRE 17 -1 (2500 3975)(2500 4075);
WIRE 17 -1 (2500 4075)(2500 4175);
WIRE 17 -1 (2500 4175)(2500 4275);
WIRE 17 -1 (2500 4275)(2500 4375);
WIRE 17 -1 (2500 4375)(2500 4475);
WIRE 17 -1 (2500 4475)(2500 4575);
WIRE 17 -1 (2500 4575)(2500 4675);
WIRE 17 -1 (3300 4900)(2500 4900);
FORCEPROP 2 LAST SIG_NAME M_G_DQS_DP<17:0>
J 0
(2725 4910);
DISPLAY 0.617021 (2725 4910);
PAINT ORANGE (2725 4910);
WIRE 17 -1 (2500 4875)(2500 4900);
WIRE 17 -1 (2500 4675)(2500 4775);
WIRE 17 -1 (2500 4775)(2500 4875);
WIRE 17 -1 (625 4275)(175 4275);
FORCEPROP 2 LAST SIG_NAME M_G_DQ<63:0>
J 0
(215 4285);
DISPLAY 0.617021 (215 4285);
PAINT ORANGE (215 4285);
WIRE 17 -1 (175 4275)(175 4250);
WIRE 17 -1 (175 4200)(175 4250);
WIRE 17 -1 (175 4150)(175 4200);
WIRE 17 -1 (175 4100)(175 4150);
WIRE 17 -1 (175 4050)(175 4100);
WIRE 17 -1 (175 4000)(175 4050);
WIRE 17 -1 (175 3950)(175 4000);
WIRE 17 -1 (175 3900)(175 3950);
WIRE 17 -1 (175 3850)(175 3900);
WIRE 17 -1 (175 3800)(175 3850);
WIRE 17 -1 (175 3750)(175 3800);
WIRE 17 -1 (175 1100)(175 1150);
WIRE 17 -1 (175 3700)(175 3750);
WIRE 17 -1 (175 3650)(175 3700);
WIRE 17 -1 (175 1150)(175 1200);
WIRE 17 -1 (175 1200)(175 1250);
WIRE 17 -1 (175 3600)(175 3650);
WIRE 17 -1 (175 3550)(175 3600);
WIRE 17 -1 (175 1250)(175 1300);
WIRE 17 -1 (175 1300)(175 1350);
WIRE 17 -1 (175 3500)(175 3550);
WIRE 17 -1 (175 3450)(175 3500);
WIRE 17 -1 (175 1350)(175 1400);
WIRE 17 -1 (175 1400)(175 1450);
WIRE 17 -1 (175 3400)(175 3450);
WIRE 17 -1 (175 3350)(175 3400);
WIRE 17 -1 (175 1450)(175 1500);
WIRE 17 -1 (175 1500)(175 1550);
WIRE 17 -1 (175 3300)(175 3350);
WIRE 17 -1 (175 3250)(175 3300);
WIRE 17 -1 (175 1550)(175 1600);
WIRE 17 -1 (175 1600)(175 1650);
WIRE 17 -1 (175 3200)(175 3250);
WIRE 17 -1 (175 3150)(175 3200);
WIRE 17 -1 (175 1650)(175 1700);
WIRE 17 -1 (175 1700)(175 1750);
WIRE 17 -1 (175 3100)(175 3150);
WIRE 17 -1 (175 3050)(175 3100);
WIRE 17 -1 (175 1750)(175 1800);
WIRE 17 -1 (175 1800)(175 1850);
WIRE 17 -1 (175 3000)(175 3050);
WIRE 17 -1 (175 2950)(175 3000);
WIRE 17 -1 (175 1850)(175 1900);
WIRE 17 -1 (175 1900)(175 1950);
WIRE 17 -1 (175 2900)(175 2950);
WIRE 17 -1 (175 2850)(175 2900);
WIRE 17 -1 (175 1950)(175 2000);
WIRE 17 -1 (175 2000)(175 2050);
WIRE 17 -1 (175 2800)(175 2850);
WIRE 17 -1 (175 2750)(175 2800);
WIRE 17 -1 (175 2050)(175 2100);
WIRE 17 -1 (175 2100)(175 2150);
WIRE 17 -1 (175 2700)(175 2750);
WIRE 17 -1 (175 2650)(175 2700);
WIRE 17 -1 (175 2150)(175 2200);
WIRE 17 -1 (175 2200)(175 2250);
WIRE 17 -1 (175 2600)(175 2650);
WIRE 17 -1 (175 2550)(175 2600);
WIRE 17 -1 (175 2250)(175 2300);
WIRE 17 -1 (175 2300)(175 2350);
WIRE 17 -1 (175 2500)(175 2550);
WIRE 17 -1 (175 2450)(175 2500);
WIRE 17 -1 (175 2350)(175 2400);
WIRE 17 -1 (175 2400)(175 2450);
WIRE 17 -1 (-1425 3400)(-1425 3450);
WIRE 17 -1 (-1425 3450)(-1425 3500);
WIRE 17 -1 (-1425 3500)(-1425 3550);
WIRE 17 -1 (-1425 3550)(-1425 3600);
WIRE 17 -1 (-1425 3600)(-1425 3650);
WIRE 17 -1 (-1425 3650)(-1425 3700);
WIRE 17 -1 (-1425 3700)(-1425 3750);
WIRE 17 -1 (-1425 3750)(-1425 3800);
WIRE 17 -1 (-1425 3800)(-1425 3850);
WIRE 17 -1 (-1425 3850)(-1425 3900);
WIRE 17 -1 (-1425 3900)(-1425 3950);
WIRE 17 -1 (-1425 3950)(-1425 4000);
WIRE 17 -1 (-1975 4275)(-1425 4275);
FORCEPROP 2 LAST SIG_NAME M_G_MA<17:0>
J 0
(-1950 4285);
DISPLAY 0.617021 (-1950 4285);
PAINT ORANGE (-1950 4285);
WIRE 17 -1 (-1425 4000)(-1425 4050);
WIRE 17 -1 (-1425 4050)(-1425 4100);
WIRE 17 -1 (-1425 4250)(-1425 4275);
WIRE 17 -1 (-1425 4200)(-1425 4250);
WIRE 17 -1 (-1425 4100)(-1425 4150);
WIRE 17 -1 (-1425 4150)(-1425 4200);
WIRE 17 -1 (-1425 3350)(-1975 3350);
FORCEPROP 2 LAST SIG_NAME M_G_BA<1:0>
J 0
(-1950 3360);
DISPLAY 0.617021 (-1950 3360);
PAINT ORANGE (-1950 3360);
WIRE 17 -1 (-1425 3350)(-1425 3300);
WIRE 17 -1 (-1425 3250)(-1425 3300);
WIRE 17 -1 (-1425 3225)(-1975 3225);
FORCEPROP 2 LAST SIG_NAME M_G_BG<1:0>
J 0
(-1950 3235);
DISPLAY 0.617021 (-1950 3235);
PAINT ORANGE (-1950 3235);
WIRE 17 -1 (-1425 3225)(-1425 3200);
WIRE 17 -1 (-1425 3150)(-1425 3200);
WIRE 17 -1 (-1625 3050)(-1975 3050);
FORCEPROP 2 LAST SIG_NAME M_G_CLK_DN<3:0>
J 0
(-1975 3060);
DISPLAY 0.617021 (-1975 3060);
PAINT ORANGE (-1975 3060);
WIRE 17 -1 (-1625 3050)(-1625 3000);
WIRE 17 -1 (-1625 3000)(-1625 2900);
WIRE 17 -1 (-1425 2775)(-1975 2775);
FORCEPROP 2 LAST SIG_NAME M_G_CS_N<7:0>
J 0
(-1950 2785);
DISPLAY 0.617021 (-1950 2785);
PAINT ORANGE (-1950 2785);
WIRE 17 -1 (-1425 2775)(-1425 2750);
WIRE 17 -1 (-1425 2700)(-1425 2750);
WIRE 17 -1 (-1425 2650)(-1425 2700);
WIRE 17 -1 (-1425 2600)(-1425 2650);
WIRE 17 -1 (-1425 3100)(-1975 3100);
FORCEPROP 2 LAST SIG_NAME M_G_CLK_DP<3:0>
J 0
(-1975 3110);
DISPLAY 0.617021 (-1975 3110);
PAINT ORANGE (-1975 3110);
WIRE 17 -1 (-1425 3100)(-1425 3050);
WIRE 17 -1 (-1425 2950)(-1425 3050);
WIRE 17 -1 (-1425 2525)(-1975 2525);
FORCEPROP 2 LAST SIG_NAME M_G_CKE<3:0>
J 0
(-1950 2535);
DISPLAY 0.617021 (-1950 2535);
PAINT ORANGE (-1950 2535);
WIRE 17 -1 (-1425 2525)(-1425 2500);
WIRE 17 -1 (-1425 2450)(-1425 2500);
WIRE 17 -1 (-1425 2375)(-1975 2375);
FORCEPROP 2 LAST SIG_NAME M_G_ODT<3:0>
J 0
(-1950 2385);
DISPLAY 0.617021 (-1950 2385);
PAINT ORANGE (-1950 2385);
WIRE 17 -1 (-1425 2375)(-1425 2350);
WIRE 17 -1 (-1425 2300)(-1425 2350);
WIRE 17 -1 (-1425 1850)(-1425 1900);
WIRE 17 -1 (-1425 1900)(-1425 1950);
WIRE 17 -1 (-1425 1950)(-1425 2000);
WIRE 17 -1 (-1425 2000)(-1425 2050);
WIRE 17 -1 (-1425 2050)(-1425 2100);
WIRE 17 -1 (-1425 2225)(-1975 2225);
FORCEPROP 2 LAST SIG_NAME M_G_ECC<7:0>
J 0
(-1950 2235);
DISPLAY 0.617021 (-1950 2235);
PAINT ORANGE (-1950 2235);
WIRE 17 -1 (-1425 2225)(-1425 2200);
WIRE 17 -1 (-1425 2100)(-1425 2150);
WIRE 17 -1 (-1425 2150)(-1425 2200);
WIRE 16 -1 (-1125 3725)(-1325 3725);
WIRE 16 -1 (2600 3200)(2200 3200);
WIRE 16 -1 (75 4025)(-125 4025);
WIRE 16 -1 (2400 3650)(2200 3650);
WIRE 16 -1 (2600 3600)(2200 3600);
WIRE 16 -1 (75 3925)(-125 3925);
WIRE 16 -1 (-2675 1075)(-2675 975);
WIRE 16 -1 (-2775 1075)(-2675 1075);
WIRE 16 -1 (-1125 1075)(-2675 1075);
FORCEPROP 2 LAST SIG_NAME M_G_VREF
J 0
(-2425 1085);
DISPLAY 0.617021 (-2425 1085);
PAINT ORANGE (-2425 1085);
WIRE 16 -1 (-1125 1525)(-2125 1525);
FORCEPROP 2 LAST SIG_NAME M_G_ACT_N
J 0
(-2075 1535);
DISPLAY 0.617021 (-2075 1535);
PAINT ORANGE (-2075 1535);
WIRE 16 -1 (-1125 1575)(-2150 1575);
FORCEPROP 2 LAST SIG_NAME M_G_ALERT_N
J 0
(-2100 1585);
DISPLAY 0.617021 (-2100 1585);
PAINT ORANGE (-2100 1585);
WIRE 16 -1 (-1975 975)(-1125 975);
FORCEPROP 2 LAST SIG_NAME TP_CH_G_DIMM0_RFU_2
J 0
(-1925 985);
DISPLAY 0.617021 (-1925 985);
PAINT ORANGE (-1925 985);
FORCEPROP 2 LASTPROP $XRERR UNIQUE?
J 0
(-2215 975);
DISPLAY 0.638298 (-2215 975);
PAINT MONO (-2215 975);
DISPLAY INVISIBLE (-2215 975);
WIRE 16 -1 (-1975 875)(-1125 875);
FORCEPROP 2 LAST SIG_NAME TP_CH_G_DIMM0_RFU_0
J 0
(-1925 885);
DISPLAY 0.617021 (-1925 885);
PAINT ORANGE (-1925 885);
FORCEPROP 2 LASTPROP $XRERR UNIQUE?
J 0
(-2215 875);
DISPLAY 0.638298 (-2215 875);
PAINT MONO (-2215 875);
DISPLAY INVISIBLE (-2215 875);
WIRE 16 -1 (-1975 925)(-1125 925);
FORCEPROP 2 LAST SIG_NAME TP_CH_G_DIMM0_RFU_1
J 0
(-1925 935);
DISPLAY 0.617021 (-1925 935);
PAINT ORANGE (-1925 935);
FORCEPROP 2 LASTPROP $XRERR UNIQUE?
J 0
(-2215 925);
DISPLAY 0.638298 (-2215 925);
PAINT MONO (-2215 925);
DISPLAY INVISIBLE (-2215 925);
WIRE 16 -1 (-1975 775)(-1125 775);
FORCEPROP 2 LAST SIG_NAME FM_ADR_COMPLETE_GHJ_N
J 0
(-1925 785);
DISPLAY 0.617021 (-1925 785);
PAINT ORANGE (-1925 785);
WIRE 16 -1 (-1575 1875)(-2300 1875);
FORCEPROP 2 LAST SIG_NAME FM_DIMM_EVENT_COD_N
J 0
(-2260 1889);
DISPLAY 0.617021 (-2260 1889);
PAINT ORANGE (-2260 1889);
WIRE 16 -1 (-1575 1625)(-1575 1875);
WIRE 16 -1 (-1575 1625)(-1125 1625);
WIRE 16 -1 (-1975 1225)(-1125 1225);
WIRE 16 -1 (-1975 1175)(-1125 1175);
FORCEPROP 2 LAST SIG_NAME SMB_DDR_GHJ_VPP_SCL
J 0
(-1935 1185);
DISPLAY 0.617021 (-1935 1185);
PAINT ORANGE (-1935 1185);
WIRE 16 -1 (-1125 2025)(-1325 2025);
WIRE 16 -1 (-1125 1975)(-1325 1975);
WIRE 16 -1 (-1125 1925)(-1325 1925);
WIRE 16 -1 (-1125 1875)(-1325 1875);
WIRE 16 -1 (-1125 1825)(-1325 1825);
WIRE 16 -1 (-1125 1725)(-1475 1725);
WIRE 16 -1 (-1475 1725)(-1475 2175);
WIRE 16 -1 (-1475 2175)(-1975 2175);
FORCEPROP 2 LAST SIG_NAME M_G_PAR
J 0
(-1950 2185);
DISPLAY 0.617021 (-1950 2185);
PAINT ORANGE (-1950 2185);
WIRE 16 -1 (-1125 1675)(-1525 1675);
WIRE 16 -1 (-1525 1675)(-1525 2125);
WIRE 16 -1 (-1525 2125)(-1975 2125);
FORCEPROP 2 LAST SIG_NAME M_GHJ_RST_N
J 0
(-1950 2135);
DISPLAY 0.617021 (-1950 2135);
PAINT ORANGE (-1950 2135);
WIRE 16 -1 (-1125 2125)(-1325 2125);
WIRE 16 -1 (-1125 2075)(-1325 2075);
WIRE 16 -1 (-1125 2175)(-1325 2175);
WIRE 16 -1 (-1125 2275)(-1325 2275);
WIRE 16 -1 (-1125 2325)(-1325 2325);
WIRE 16 -1 (-1125 2475)(-1325 2475);
WIRE 16 -1 (-1125 2425)(-1325 2425);
WIRE 16 -1 (-1125 2975)(-1525 2975);
WIRE 16 -1 (-1125 2925)(-1325 2925);
WIRE 16 -1 (-1125 2725)(-1325 2725);
WIRE 16 -1 (-1125 3025)(-1325 3025);
WIRE 16 -1 (-1125 2675)(-1325 2675);
WIRE 16 -1 (-1125 2625)(-1325 2625);
WIRE 16 -1 (-1125 2575)(-1325 2575);
WIRE 16 -1 (-1125 2875)(-1525 2875);
WIRE 16 -1 (-1275 2775)(-1125 2775);
WIRE 16 -1 (-1275 2825)(-1975 2825);
FORCEPROP 2 LAST SIG_NAME M_G_C<2>
J 0
(-1950 2835);
DISPLAY 0.617021 (-1950 2835);
PAINT ORANGE (-1950 2835);
WIRE 16 -1 (-1275 2825)(-1275 2775);
WIRE 16 -1 (-1125 3275)(-1325 3275);
WIRE 16 -1 (-1125 3375)(-1325 3375);
WIRE 16 -1 (-1125 3425)(-1325 3425);
WIRE 16 -1 (-1125 3525)(-1325 3525);
WIRE 16 -1 (-1125 3575)(-1325 3575);
WIRE 16 -1 (-1125 3125)(-1325 3125);
WIRE 16 -1 (-1125 3175)(-1325 3175);
WIRE 16 -1 (-1125 3225)(-1325 3225);
WIRE 16 -1 (-1125 3475)(-1325 3475);
WIRE 16 -1 (-1125 3975)(-1325 3975);
WIRE 16 -1 (-1125 4025)(-1325 4025);
WIRE 16 -1 (-1125 3625)(-1325 3625);
WIRE 16 -1 (-1125 3675)(-1325 3675);
WIRE 16 -1 (-1125 3775)(-1325 3775);
WIRE 16 -1 (-1125 3825)(-1325 3825);
WIRE 16 -1 (-1125 3875)(-1325 3875);
WIRE 16 -1 (-1125 3925)(-1325 3925);
WIRE 16 -1 (-1125 4075)(-1325 4075);
WIRE 16 -1 (-1125 4225)(-1325 4225);
WIRE 16 -1 (-1125 4125)(-1325 4125);
WIRE 16 -1 (-1125 4175)(-1325 4175);
WIRE 16 -1 (75 4225)(-125 4225);
WIRE 16 -1 (75 2525)(-125 2525);
WIRE 16 -1 (75 2475)(-125 2475);
WIRE 16 -1 (75 4175)(-125 4175);
WIRE 16 -1 (75 4125)(-125 4125);
WIRE 16 -1 (75 4075)(-125 4075);
WIRE 16 -1 (75 3875)(-125 3875);
WIRE 16 -1 (75 3825)(-125 3825);
WIRE 16 -1 (75 3375)(-125 3375);
WIRE 16 -1 (75 3325)(-125 3325);
WIRE 16 -1 (75 3275)(-125 3275);
WIRE 16 -1 (75 3225)(-125 3225);
WIRE 16 -1 (75 3175)(-125 3175);
WIRE 16 -1 (75 3125)(-125 3125);
WIRE 16 -1 (75 3075)(-125 3075);
WIRE 16 -1 (75 3025)(-125 3025);
WIRE 16 -1 (75 2925)(-125 2925);
WIRE 16 -1 (75 2775)(-125 2775);
WIRE 16 -1 (75 2725)(-125 2725);
WIRE 16 -1 (75 2675)(-125 2675);
WIRE 16 -1 (75 2625)(-125 2625);
WIRE 16 -1 (75 2575)(-125 2575);
WIRE 16 -1 (75 2325)(-125 2325);
WIRE 16 -1 (75 2275)(-125 2275);
WIRE 16 -1 (75 2225)(-125 2225);
WIRE 16 -1 (75 2175)(-125 2175);
WIRE 16 -1 (75 2125)(-125 2125);
WIRE 16 -1 (75 2075)(-125 2075);
WIRE 16 -1 (75 2025)(-125 2025);
WIRE 16 -1 (75 1975)(-125 1975);
WIRE 16 -1 (75 1875)(-125 1875);
WIRE 16 -1 (75 1775)(-125 1775);
WIRE 16 -1 (75 1725)(-125 1725);
WIRE 16 -1 (75 1675)(-125 1675);
WIRE 16 -1 (75 1625)(-125 1625);
WIRE 16 -1 (75 1525)(-125 1525);
WIRE 16 -1 (75 1425)(-125 1425);
WIRE 16 -1 (75 1375)(-125 1375);
WIRE 16 -1 (75 1125)(-125 1125);
WIRE 16 -1 (75 1075)(-125 1075);
WIRE 16 -1 (75 2825)(-125 2825);
WIRE 16 -1 (75 2875)(-125 2875);
WIRE 16 -1 (75 2975)(-125 2975);
WIRE 16 -1 (75 2375)(-125 2375);
WIRE 16 -1 (75 1825)(-125 1825);
WIRE 16 -1 (75 1925)(-125 1925);
WIRE 16 -1 (75 3975)(-125 3975);
WIRE 16 -1 (75 3775)(-125 3775);
WIRE 16 -1 (75 3725)(-125 3725);
WIRE 16 -1 (75 3675)(-125 3675);
WIRE 16 -1 (75 3625)(-125 3625);
WIRE 16 -1 (75 3575)(-125 3575);
WIRE 16 -1 (75 3525)(-125 3525);
WIRE 16 -1 (75 3475)(-125 3475);
WIRE 16 -1 (75 3425)(-125 3425);
WIRE 16 -1 (75 1175)(-125 1175);
WIRE 16 -1 (75 1225)(-125 1225);
WIRE 16 -1 (75 1275)(-125 1275);
WIRE 16 -1 (75 1325)(-125 1325);
WIRE 16 -1 (75 1575)(-125 1575);
WIRE 16 -1 (75 1475)(-125 1475);
WIRE 16 -1 (75 2425)(-125 2425);
WIRE 16 -1 (2400 3150)(2200 3150);
WIRE 16 -1 (2400 3250)(2200 3250);
WIRE 16 -1 (2400 3350)(2200 3350);
WIRE 16 -1 (2400 3450)(2200 3450);
WIRE 16 -1 (2400 3550)(2200 3550);
WIRE 16 -1 (2400 3750)(2200 3750);
WIRE 16 -1 (2400 3850)(2200 3850);
WIRE 16 -1 (2400 3950)(2200 3950);
WIRE 16 -1 (2400 4050)(2200 4050);
WIRE 16 -1 (2600 3100)(2200 3100);
WIRE 16 -1 (2600 3300)(2200 3300);
WIRE 16 -1 (2600 3400)(2200 3400);
WIRE 16 -1 (2600 3500)(2200 3500);
WIRE 16 -1 (2600 3700)(2200 3700);
WIRE 16 -1 (2600 3800)(2200 3800);
WIRE 16 -1 (2600 3900)(2200 3900);
WIRE 16 -1 (2600 4000)(2200 4000);
WIRE 16 -1 (2400 4150)(2200 4150);
WIRE 16 -1 (2400 4250)(2200 4250);
WIRE 16 -1 (2400 4350)(2200 4350);
WIRE 16 -1 (2400 4450)(2200 4450);
WIRE 16 -1 (2400 4550)(2200 4550);
WIRE 16 -1 (2400 4650)(2200 4650);
WIRE 16 -1 (2400 4750)(2200 4750);
WIRE 16 -1 (2400 4850)(2200 4850);
WIRE 16 -1 (2600 4100)(2200 4100);
WIRE 16 -1 (2600 4200)(2200 4200);
WIRE 16 -1 (2600 4300)(2200 4300);
WIRE 16 -1 (2600 4400)(2200 4400);
WIRE 16 -1 (2600 4500)(2200 4500);
WIRE 16 -1 (2600 4600)(2200 4600);
WIRE 16 -1 (2600 4700)(2200 4700);
WIRE 16 -1 (2600 4800)(2200 4800);
DOT 1 (2850 2950);
DOT 1 (4250 2850);
DOT 1 (4250 2650);
DOT 1 (750 2450);
DOT 1 (750 2150);
DOT 1 (750 2100);
DOT 1 (750 1000);
DOT 1 (2850 3100);
DOT 1 (-1350 1375);
DOT 1 (-1425 1425);
DOT 1 (-2675 1075);
DOT 1 (750 950);
DOT 1 (750 1050);
DOT 1 (750 1100);
DOT 1 (750 1150);
DOT 1 (750 1200);
DOT 1 (750 1300);
DOT 1 (750 1250);
DOT 1 (750 1400);
DOT 1 (750 1350);
DOT 1 (750 1450);
DOT 1 (750 1500);
DOT 1 (750 1550);
DOT 1 (750 1600);
DOT 1 (750 1650);
DOT 1 (750 1700);
DOT 1 (750 1800);
DOT 1 (750 1750);
DOT 1 (750 1850);
DOT 1 (750 1900);
DOT 1 (750 1950);
DOT 1 (750 2000);
DOT 1 (750 2050);
DOT 1 (750 2300);
DOT 1 (750 2500);
DOT 1 (750 2550);
DOT 1 (750 2600);
DOT 1 (2850 950);
DOT 1 (2850 900);
DOT 1 (2850 850);
DOT 1 (2850 1050);
DOT 1 (2850 1000);
DOT 1 (2850 1200);
DOT 1 (2850 1150);
DOT 1 (2850 1100);
DOT 1 (2850 1300);
DOT 1 (2850 1250);
DOT 1 (2850 1450);
DOT 1 (2850 1400);
DOT 1 (2850 1350);
DOT 1 (2850 1550);
DOT 1 (2850 1500);
DOT 1 (2850 1600);
DOT 1 (2850 1700);
DOT 1 (2850 1650);
DOT 1 (2850 1750);
DOT 1 (2850 1800);
DOT 1 (2850 1850);
DOT 1 (2150 2600);
DOT 1 (2850 1950);
DOT 1 (2850 1900);
DOT 1 (2850 2100);
DOT 1 (2850 2050);
DOT 1 (2850 2000);
DOT 1 (2850 2200);
DOT 1 (2850 2150);
DOT 1 (2850 2350);
DOT 1 (2850 2300);
DOT 1 (2850 2250);
DOT 1 (2850 2400);
DOT 1 (2850 2450);
DOT 1 (2850 2500);
DOT 1 (2850 2600);
DOT 1 (2850 2550);
DOT 1 (2850 2700);
DOT 1 (2850 2650);
DOT 1 (2850 2750);
DOT 1 (2850 2850);
DOT 1 (2850 2800);
DOT 1 (2850 2900);
DOT 1 (2850 3000);
DOT 1 (2850 3050);
DOT 1 (4250 900);
DOT 1 (4250 850);
DOT 1 (4250 950);
DOT 1 (4250 1000);
DOT 1 (4250 1050);
DOT 1 (4250 1200);
DOT 1 (4250 1150);
DOT 1 (4250 1100);
DOT 1 (4250 1250);
DOT 1 (4250 1300);
DOT 1 (4250 1450);
DOT 1 (4250 1400);
DOT 1 (4250 1350);
DOT 1 (4250 1500);
DOT 1 (4250 1550);
DOT 1 (4250 1600);
DOT 1 (4250 1700);
DOT 1 (4250 1650);
DOT 1 (4250 1750);
DOT 1 (4250 1800);
DOT 1 (4250 1850);
DOT 1 (4250 1950);
DOT 1 (4250 1900);
DOT 1 (4250 2100);
DOT 1 (4250 2050);
DOT 1 (4250 2000);
DOT 1 (4250 2150);
DOT 1 (4250 2200);
DOT 1 (4250 2350);
DOT 1 (4250 2300);
DOT 1 (4250 2250);
DOT 1 (4250 2450);
DOT 1 (4250 2400);
DOT 1 (4250 2500);
DOT 1 (4250 2600);
DOT 1 (4250 2550);
DOT 1 (4250 2700);
DOT 1 (4250 2750);
DOT 1 (4250 2800);
DOT 1 (4250 3000);
DOT 1 (4250 2950);
DOT 1 (4250 2900);
DOT 1 (4250 3050);
DOT 1 (4250 3100);
FORCENOTE
PVDDQ (SINGLE SIDE) CAP: 10UF X1, 22UF X50
(-1100 4850) 0;
DISPLAY LEFT (-1100 4850);
DISPLAY 1.021277 (-1100 4850);
PAINT PURPLE (-1100 4850);
FORCENOTE
PVDDQ (DOUBLE SIDE) CAP: 100UF X8, 47UF X41
(-1100 4800) 0;
DISPLAY LEFT (-1100 4800);
DISPLAY 1.021277 (-1100 4800);
PAINT PURPLE (-1100 4800);
FORCENOTE
CAP BETWEEN DIMM
(-1100 5025) 0;
DISPLAY LEFT (-1100 5025);
DISPLAY 1.276596 (-1100 5025);
PAINT PURPLE (-1100 5025);
FORCENOTE
PVPP CAP: 10UF X12
(-1100 4950) 0;
DISPLAY LEFT (-1100 4950);
DISPLAY 1.021277 (-1100 4950);
PAINT PURPLE (-1100 4950);
FORCENOTE
PVTT CAP: 100UF X2, 47UF X1
(-1100 4900) 0;
DISPLAY LEFT (-1100 4900);
DISPLAY 1.021277 (-1100 4900);
PAINT PURPLE (-1100 4900);
FORCENOTE
SMBUS ADDR: 0XA2
(-3550 400) 0;
DISPLAY LEFT (-3550 400);
DISPLAY 1.574468 (-3550 400);
PAINT PURPLE (-3550 400);
FORCENOTE
PLACE CAP NEAR DIMM CONNECTOR
(-2938 527) 0;
DISPLAY LEFT (-2938 527);
DISPLAY 1.574468 (-2938 527);
PAINT PURPLE (-2938 527);
QUIT
